G04 ================== begin FILE IDENTIFICATION RECORD ==================*
G04 Layout Name:  15105-sa.brd*
G04 Film Name:    L5VCC*
G04 File Format:  Gerber RS274X*
G04 File Origin:  Cadence Allegro 16.5-S056*
G04 Origin Date:  Wed Nov 16 02:02:21 2016*
G04 *
G04 Layer:  VIA CLASS/L5VCC*
G04 Layer:  PIN/L5VCC*
G04 Layer:  PACKAGE GEOMETRY/PWRVCC*
G04 Layer:  ETCH/L5VCC*
G04 Layer:  DRAWING FORMAT/LAYER_PCB_STORY*
G04 Layer:  DRAWING FORMAT/LAYER_L5VCC*
G04 *
G04 Offset:    (0.00 0.00)*
G04 Mirror:    No*
G04 Mode:      Negative*
G04 Rotation:  0*
G04 FullContactRelief:  No*
G04 UndefLineWidth:     6.00*
G04 ================== end FILE IDENTIFICATION RECORD ====================*
%FSLAX35Y35*MOIN*%
%IR0*IPPOS*OFA0.00000B0.00000*MIA0B0*SFA1.00000B1.00000*%
%AMMACRO29*
4,1,13,.02632,.01218,
.028035,.007425,
.028899,.002443,
.028884,-.002612,
.027991,-.007588,
.02632,-.01218,
.03005,-.01591,
.032356,-.01045,
.033679,-.004673,
.033979,.001247,
.033246,.007128,
.031504,.012793,
.03005,.01591,
.02632,.01218,
0.0*
4,1,13,.01218,-.02632,
.007425,-.028035,
.002443,-.028899,
-.002612,-.028884,
-.007588,-.027991,
-.01218,-.02632,
-.01591,-.03005,
-.01045,-.032356,
-.004673,-.033679,
.001247,-.033979,
.007128,-.033246,
.012793,-.031504,
.01591,-.03005,
.01218,-.02632,
0.0*
4,1,13,-.02632,-.01218,
-.028035,-.007425,
-.028899,-.002443,
-.028884,.002612,
-.027991,.007588,
-.02632,.01218,
-.03005,.01591,
-.032356,.01045,
-.033679,.004673,
-.033979,-.001247,
-.033246,-.007128,
-.031504,-.012793,
-.03005,-.01591,
-.02632,-.01218,
0.0*
4,1,13,-.01218,.02632,
-.007425,.028035,
-.002443,.028899,
.002612,.028884,
.007588,.027991,
.01218,.02632,
.01591,.03005,
.01045,.032356,
.004673,.033679,
-.001247,.033979,
-.007128,.033246,
-.012793,.031504,
-.01591,.03005,
-.01218,.02632,
0.0*
%
%ADD29MACRO29*%
%ADD14C,.03*%
%ADD24C,.032*%
%ADD21C,.06*%
%ADD35C,.043*%
%ADD32C,.07*%
%ADD36C,.063*%
%ADD26C,.036*%
%ADD13C,.09*%
%ADD25C,.028*%
%ADD18C,.064*%
%ADD23C,.066*%
%ADD31C,.058*%
%ADD28C,.068*%
%ADD12C,.078*%
%AMMACRO20*
4,1,15,.00398,.00044,
.003999,.000208,
.004004,-.000025,
.003996,-.000258,
.00398,-.00044,
.00483,-.00129,
.004897,-.001007,
.004947,-.000721,
.004981,-.000432,
.004997,-.000141,
.004997,.000149,
.00498,.00044,
.004946,.000729,
.004895,.001015,
.00483,.00129,
.00398,.00044,
90.*
4,1,15,.00044,-.00398,
.000208,-.003999,
-.000025,-.004004,
-.000258,-.003996,
-.00044,-.00398,
-.00129,-.00483,
-.001007,-.004897,
-.000721,-.004947,
-.000432,-.004981,
-.000141,-.004997,
.000149,-.004997,
.00044,-.00498,
.000729,-.004946,
.001015,-.004895,
.00129,-.00483,
.00044,-.00398,
90.*
4,1,15,-.00398,-.00044,
-.003999,-.000208,
-.004004,.000025,
-.003996,.000258,
-.00398,.00044,
-.00483,.00129,
-.004897,.001007,
-.004947,.000721,
-.004981,.000432,
-.004997,.000141,
-.004997,-.000149,
-.00498,-.00044,
-.004946,-.000729,
-.004895,-.001015,
-.00483,-.00129,
-.00398,-.00044,
90.*
4,1,15,-.00044,.00398,
-.000208,.003999,
.000025,.004004,
.000258,.003996,
.00044,.00398,
.00129,.00483,
.001007,.004897,
.000721,.004947,
.000432,.004981,
.000141,.004997,
-.000149,.004997,
-.00044,.00498,
-.000729,.004946,
-.001015,.004895,
-.00129,.00483,
-.00044,.00398,
90.*
%
%ADD20MACRO20*%
%AMMACRO11*
4,1,15,.00398,.00044,
.003999,.000208,
.004004,-.000025,
.003996,-.000258,
.00398,-.00044,
.00483,-.00129,
.004897,-.001007,
.004947,-.000721,
.004981,-.000432,
.004997,-.000141,
.004997,.000149,
.00498,.00044,
.004946,.000729,
.004895,.001015,
.00483,.00129,
.00398,.00044,
0.0*
4,1,15,.00044,-.00398,
.000208,-.003999,
-.000025,-.004004,
-.000258,-.003996,
-.00044,-.00398,
-.00129,-.00483,
-.001007,-.004897,
-.000721,-.004947,
-.000432,-.004981,
-.000141,-.004997,
.000149,-.004997,
.00044,-.00498,
.000729,-.004946,
.001015,-.004895,
.00129,-.00483,
.00044,-.00398,
0.0*
4,1,15,-.00398,-.00044,
-.003999,-.000208,
-.004004,.000025,
-.003996,.000258,
-.00398,.00044,
-.00483,.00129,
-.004897,.001007,
-.004947,.000721,
-.004981,.000432,
-.004997,.000141,
-.004997,-.000149,
-.00498,-.00044,
-.004946,-.000729,
-.004895,-.001015,
-.00483,-.00129,
-.00398,-.00044,
0.0*
4,1,15,-.00044,.00398,
-.000208,.003999,
.000025,.004004,
.000258,.003996,
.00044,.00398,
.00129,.00483,
.001007,.004897,
.000721,.004947,
.000432,.004981,
.000141,.004997,
-.000149,.004997,
-.00044,.00498,
-.000729,.004946,
-.001015,.004895,
-.00129,.00483,
-.00044,.00398,
0.0*
%
%ADD11MACRO11*%
%AMMACRO33*
4,1,13,.02632,.01218,
.028035,.007425,
.028899,.002443,
.028884,-.002612,
.027991,-.007588,
.02632,-.01218,
.03005,-.01591,
.032356,-.01045,
.033679,-.004673,
.033979,.001247,
.033246,.007128,
.031504,.012793,
.03005,.01591,
.02632,.01218,
180.*
4,1,13,.01218,-.02632,
.007425,-.028035,
.002443,-.028899,
-.002612,-.028884,
-.007588,-.027991,
-.01218,-.02632,
-.01591,-.03005,
-.01045,-.032356,
-.004673,-.033679,
.001247,-.033979,
.007128,-.033246,
.012793,-.031504,
.01591,-.03005,
.01218,-.02632,
180.*
4,1,13,-.02632,-.01218,
-.028035,-.007425,
-.028899,-.002443,
-.028884,.002612,
-.027991,.007588,
-.02632,.01218,
-.03005,.01591,
-.032356,.01045,
-.033679,.004673,
-.033979,-.001247,
-.033246,-.007128,
-.031504,-.012793,
-.03005,-.01591,
-.02632,-.01218,
180.*
4,1,13,-.01218,.02632,
-.007425,.028035,
-.002443,.028899,
.002612,.028884,
.007588,.027991,
.01218,.02632,
.01591,.03005,
.01045,.032356,
.004673,.033679,
-.001247,.033979,
-.007128,.033246,
-.012793,.031504,
-.01591,.03005,
-.01218,.02632,
180.*
%
%ADD33MACRO33*%
%ADD10C,.114*%
%ADD19C,.208*%
%ADD16C,.19*%
%ADD22C,.119*%
%ADD17C,.156*%
%ADD30C,.166*%
%AMMACRO15*
4,1,15,.00398,.00044,
.003999,.000208,
.004004,-.000025,
.003996,-.000258,
.00398,-.00044,
.00483,-.00129,
.004897,-.001007,
.004947,-.000721,
.004981,-.000432,
.004997,-.000141,
.004997,.000149,
.00498,.00044,
.004946,.000729,
.004895,.001015,
.00483,.00129,
.00398,.00044,
270.*
4,1,15,.00044,-.00398,
.000208,-.003999,
-.000025,-.004004,
-.000258,-.003996,
-.00044,-.00398,
-.00129,-.00483,
-.001007,-.004897,
-.000721,-.004947,
-.000432,-.004981,
-.000141,-.004997,
.000149,-.004997,
.00044,-.00498,
.000729,-.004946,
.001015,-.004895,
.00129,-.00483,
.00044,-.00398,
270.*
4,1,15,-.00398,-.00044,
-.003999,-.000208,
-.004004,.000025,
-.003996,.000258,
-.00398,.00044,
-.00483,.00129,
-.004897,.001007,
-.004947,.000721,
-.004981,.000432,
-.004997,.000141,
-.004997,-.000149,
-.00498,-.00044,
-.004946,-.000729,
-.004895,-.001015,
-.00483,-.00129,
-.00398,-.00044,
270.*
4,1,15,-.00044,.00398,
-.000208,.003999,
.000025,.004004,
.000258,.003996,
.00044,.00398,
.00129,.00483,
.001007,.004897,
.000721,.004947,
.000432,.004981,
.000141,.004997,
-.000149,.004997,
-.00044,.00498,
-.000729,.004946,
-.001015,.004895,
-.00129,.00483,
-.00044,.00398,
270.*
%
%ADD15MACRO15*%
%AMMACRO34*
4,1,14,.05302,.02473,
.056509,.015147,
.058281,.005105,
.058282,-.005093,
.056512,-.015136,
.053025,-.02472,
.05302,-.02473,
.05676,-.02847,
.060841,-.018181,
.063074,-.00734,
.063391,.003724,
.061781,.014675,
.058294,.025181,
.05676,.02847,
.05302,.02473,
0.0*
4,1,14,.02473,-.05302,
.015147,-.056509,
.005105,-.058281,
-.005093,-.058282,
-.015136,-.056512,
-.02472,-.053025,
-.02473,-.05302,
-.02847,-.05676,
-.018181,-.060841,
-.00734,-.063074,
.003724,-.063391,
.014675,-.061781,
.025181,-.058294,
.02847,-.05676,
.02473,-.05302,
0.0*
4,1,14,-.05302,-.02473,
-.056509,-.015147,
-.058281,-.005105,
-.058282,.005093,
-.056512,.015136,
-.053025,.02472,
-.05302,.02473,
-.05676,.02847,
-.060841,.018181,
-.063074,.00734,
-.063391,-.003724,
-.061781,-.014675,
-.058294,-.025181,
-.05676,-.02847,
-.05302,-.02473,
0.0*
4,1,14,-.02473,.05302,
-.015147,.056509,
-.005105,.058281,
.005093,.058282,
.015136,.056512,
.02472,.053025,
.02473,.05302,
.02847,.05676,
.018181,.060841,
.00734,.063074,
-.003724,.063391,
-.014675,.061781,
-.025181,.058294,
-.02847,.05676,
-.02473,.05302,
0.0*
%
%ADD34MACRO34*%
%AMMACRO27*
4,1,13,.02556,.01142,
.027155,.006808,
.027924,.001989,
.027846,-.00289,
.026921,-.007681,
.02556,-.01142,
.02931,-.01517,
.031499,-.00985,
.032731,-.004231,
.032968,.001517,
.032204,.007219,
.030461,.012702,
.02931,.01517,
.02556,.01142,
0.0*
4,1,13,.01142,-.02556,
.006808,-.027155,
.001989,-.027924,
-.00289,-.027846,
-.007681,-.026921,
-.01142,-.02556,
-.01517,-.02931,
-.00985,-.031499,
-.004231,-.032731,
.001517,-.032968,
.007219,-.032204,
.012702,-.030461,
.01517,-.02931,
.01142,-.02556,
0.0*
4,1,13,-.02556,-.01142,
-.027155,-.006808,
-.027924,-.001989,
-.027846,.00289,
-.026921,.007681,
-.02556,.01142,
-.02931,.01517,
-.031499,.00985,
-.032731,.004231,
-.032968,-.001517,
-.032204,-.007219,
-.030461,-.012702,
-.02931,-.01517,
-.02556,-.01142,
0.0*
4,1,13,-.01142,.02556,
-.006808,.027155,
-.001989,.027924,
.00289,.027846,
.007681,.026921,
.01142,.02556,
.01517,.02931,
.00985,.031499,
.004231,.032731,
-.001517,.032968,
-.007219,.032204,
-.012702,.030461,
-.01517,.02931,
-.01142,.02556,
0.0*
%
%ADD27MACRO27*%
%ADD37C,.02*%
%ADD38C,.006*%
%ADD54C,.06204*%
%ADD53C,.08024*%
%ADD51C,.06404*%
%ADD46C,.05604*%
%ADD50C,.08224*%
%ADD52C,.07424*%
%ADD41C,.11004*%
%ADD42C,.10224*%
%ADD48C,.3151*%
%ADD44C,.15204*%
%ADD43C,.31404*%
%ADD47C,.31532*%
%ADD55C,.31506*%
%ADD49C,.31534*%
%ADD40O,.09222X.04822*%
%ADD39O,.09224X.04824*%
%ADD45C,.31498*%
G75*
%LPD*%
G75*
G36*
G01X-6000Y-25685D02*
X1406000D01*
Y903637D01*
X-6000D01*
Y-25685D01*
G37*
%LPC*%
G75*
G36*
G01X3937Y837547D02*
X100000D01*
G03X108122Y845669I0J8122D01*
G01Y870618D01*
X110237D01*
G03X115209Y875590I-1J4973D01*
G01Y883398D01*
X288732D01*
Y876377D01*
G03X288826Y875176I7725J0D01*
G03X295420Y868723I7631J1202D01*
G03X297493I1037J7261D01*
G03X304181Y876378I-1037J7655D01*
G01Y883398D01*
X439909D01*
Y875590D01*
G03X444881Y870618I4973J1D01*
G01X446996D01*
Y845669D01*
G03X455118Y837547I8122J0D01*
G01X517323D01*
G03X525445Y845669I0J8122D01*
G01Y870618D01*
X527560D01*
G03X532532Y875590I-1J4973D01*
G01Y883398D01*
X706055D01*
Y876377D01*
G03X706149Y875176I7725J0D01*
G03X712743Y868723I7631J1202D01*
G03X714816I1037J7261D01*
G03X721504Y876378I-1037J7655D01*
G01Y883398D01*
X857232D01*
Y875590D01*
G03X862204Y870618I4973J1D01*
G01X864319D01*
Y845669D01*
G03X872441Y837547I8122J0D01*
G01X902134D01*
G02X918815Y820866I0J-16681D01*
G01Y650669D01*
G03X926819Y642665I8004J0D01*
G01X983748D01*
G03X991752Y650669I0J8004D01*
G01Y820866D01*
G02X1008433Y837547I16681J0D01*
G01X1013386D01*
G03X1021508Y845669I0J8122D01*
G01Y870618D01*
X1023623D01*
G03X1028595Y875590I-1J4973D01*
G01Y883398D01*
X1202118D01*
Y876377D01*
G03X1202212Y875176I7725J0D01*
G03X1208806Y868723I7631J1202D01*
G03X1210879I1036J7261D01*
G03X1217567Y876378I-1037J7655D01*
G01Y883398D01*
X1353295D01*
Y875590D01*
G03X1358267Y870618I4973J1D01*
G01X1360382D01*
Y845669D01*
G03X1368504Y837547I8122J0D01*
G01X1396063D01*
G02X1396996Y836614I0J-933D01*
G01Y76626D01*
X1396653D01*
G03X1391681Y71654I0J-4972D01*
G01Y40157D01*
G03X1396653Y35185I4972J0D01*
G01X1396996D01*
Y3937D01*
G02X1396063Y3004I-933J0D01*
G01X1310039D01*
G03X1303098Y-3937I0J-6941D01*
G01Y-15748D01*
G02X1302165Y-16681I-933J0D01*
G01X486762D01*
G02X481892Y-11811I0J4870D01*
G01Y-7874D01*
G03X471014Y3004I-10878J0D01*
G01X212402D01*
G02X207532Y7874I0J4870D01*
G01Y94528D01*
G03X196654Y105406I-10878J0D01*
G01X7874D01*
G02X3004Y110276I0J4870D01*
G01Y836614D01*
G02X3937Y837547I933J0D01*
G37*
%LPD*%
G75*
G36*
G01X115226Y418475D02*
X115233Y418468D01*
X112119Y415354D01*
X112115D01*
X112113Y415356D01*
X112107D01*
G02X108619Y418688I-1701J1711D01*
G01X108694Y418775D01*
X108691Y418778D01*
X111807Y421894D01*
X111810Y421891D01*
X111897Y421966D01*
G02X115226Y418475I1621J-1787D01*
G37*
G36*
G01X621794Y85929D02*
X621802Y85934D01*
X624757Y80419D01*
X624754Y80416D01*
X624751Y80414D01*
X624779Y80355D01*
G02X620463Y77990I-2202J-1102D01*
G01X620402Y78084D01*
X620399Y78082D01*
X617444Y83599D01*
X617447Y83601D01*
X617407Y83691D01*
G02X621794Y85929I2217J1073D01*
G37*
G36*
G01X542707Y77990D02*
X542646Y78084D01*
X542643Y78082D01*
X539688Y83597D01*
X539691Y83600D01*
X539694Y83602D01*
X539666Y83661D01*
G02X544038Y85929I2202J1103D01*
G01X544046Y85934D01*
X547001Y80417D01*
X546998Y80415D01*
X547038Y80325D01*
G02X542707Y77990I-2217J-1072D01*
G37*
G36*
G01X1343726Y873166D02*
X1340525D01*
G02X1340526Y877186I1J2010D01*
G01X1343726D01*
G02Y873166I0J-2010D01*
G37*
G36*
G01X1331128D02*
X1327928D01*
G02Y877186I0J2010D01*
G01X1331129D01*
G02X1331128Y873166I-1J-2010D01*
G37*
G36*
G01X1318529D02*
X1315329D01*
G02Y877186I0J2010D01*
G01X1318530D01*
G02X1318529Y873166I-1J-2010D01*
G37*
G36*
G01X1305931D02*
X1302731D01*
G02Y877186I0J2010D01*
G01X1305932D01*
G02X1305931Y873166I-1J-2010D01*
G37*
G36*
G01X1293333D02*
X1290133D01*
G02Y877186I0J2010D01*
G01X1293334D01*
G02X1293333Y873166I-1J-2010D01*
G37*
G36*
G01X1280734D02*
X1277534D01*
G02Y877186I0J2010D01*
G01X1280735D01*
G02X1280734Y873166I-1J-2010D01*
G37*
G36*
G01X1268136D02*
X1264936D01*
G02Y877186I0J2010D01*
G01X1268137D01*
G02X1268136Y873166I-1J-2010D01*
G37*
G36*
G01X1255537D02*
X1252337D01*
G02Y877186I0J2010D01*
G01X1255538D01*
G02X1255537Y873166I-1J-2010D01*
G37*
G36*
G01X1242939D02*
X1239739D01*
G02Y877186I0J2010D01*
G01X1242940D01*
G02X1242939Y873166I-1J-2010D01*
G37*
G36*
G01X1230340D02*
X1227140D01*
G02Y877186I0J2010D01*
G01X1230341D01*
G02X1230340Y873166I-1J-2010D01*
G37*
G36*
G01X1186246D02*
X1183046D01*
G02Y877186I0J2010D01*
G01X1186247D01*
G02X1186246Y873166I-1J-2010D01*
G37*
G36*
G01X1164199D02*
X1160999D01*
G02Y877186I0J2010D01*
G01X1164200D01*
G02X1164199Y873166I-1J-2010D01*
G37*
G36*
G01X1151600D02*
X1148400D01*
G02Y877186I0J2010D01*
G01X1151601D01*
G02X1151600Y873166I-1J-2010D01*
G37*
G36*
G01X1139002D02*
X1135802D01*
G02Y877186I0J2010D01*
G01X1139003D01*
G02X1139002Y873166I-1J-2010D01*
G37*
G36*
G01X1126403D02*
X1123203D01*
G02Y877186I0J2010D01*
G01X1126404D01*
G02X1126403Y873166I-1J-2010D01*
G37*
G36*
G01X1113805D02*
X1110605D01*
G02Y877186I0J2010D01*
G01X1113806D01*
G02X1113805Y873166I-1J-2010D01*
G37*
G36*
G01X1101207D02*
X1098007D01*
G02Y877186I0J2010D01*
G01X1101208D01*
G02X1101207Y873166I-1J-2010D01*
G37*
G36*
G01X1088608D02*
X1085408D01*
G02Y877186I0J2010D01*
G01X1088609D01*
G02X1088608Y873166I-1J-2010D01*
G37*
G36*
G01X1076010D02*
X1072810D01*
G02Y877186I0J2010D01*
G01X1076011D01*
G02X1076010Y873166I-1J-2010D01*
G37*
G36*
G01X1050813D02*
X1047613D01*
G02Y877186I0J2010D01*
G01X1050814D01*
G02X1050813Y873166I-1J-2010D01*
G37*
G36*
G01X1038214D02*
X1035014D01*
G02Y877186I0J2010D01*
G01X1038215D01*
G02X1038214Y873166I-1J-2010D01*
G37*
G36*
G01X847663D02*
X844463D01*
G02Y877186I0J2010D01*
G01X847664D01*
G02X847663Y873166I-1J-2010D01*
G37*
G36*
G01X835065D02*
X831865D01*
G02Y877186I0J2010D01*
G01X835066D01*
G02X835065Y873166I-1J-2010D01*
G37*
G36*
G01X809868D02*
X806668D01*
G02Y877186I0J2010D01*
G01X809869D01*
G02X809868Y873166I-1J-2010D01*
G37*
G36*
G01X797270D02*
X794070D01*
G02Y877186I0J2010D01*
G01X797271D01*
G02X797270Y873166I-1J-2010D01*
G37*
G36*
G01X784671D02*
X781471D01*
G02Y877186I0J2010D01*
G01X784672D01*
G02X784671Y873166I-1J-2010D01*
G37*
G36*
G01X772073D02*
X768873D01*
G02Y877186I0J2010D01*
G01X772074D01*
G02X772073Y873166I-1J-2010D01*
G37*
G36*
G01X759474D02*
X756274D01*
G02Y877186I0J2010D01*
G01X759475D01*
G02X759474Y873166I-1J-2010D01*
G37*
G36*
G01X746876D02*
X743676D01*
G02Y877186I0J2010D01*
G01X746877D01*
G02X746876Y873166I-1J-2010D01*
G37*
G36*
G01X734277D02*
X731076D01*
G02X731077Y877186I1J2010D01*
G01X734277D01*
G02Y873166I0J-2010D01*
G37*
G36*
G01X690183D02*
X686983D01*
G02Y877186I0J2010D01*
G01X690184D01*
G02X690183Y873166I-1J-2010D01*
G37*
G36*
G01X677585D02*
X674385D01*
G02Y877186I0J2010D01*
G01X677586D01*
G02X677585Y873166I-1J-2010D01*
G37*
G36*
G01X664986D02*
X661786D01*
G02Y877186I0J2010D01*
G01X664987D01*
G02X664986Y873166I-1J-2010D01*
G37*
G36*
G01X652388D02*
X649188D01*
G02Y877186I0J2010D01*
G01X652389D01*
G02X652388Y873166I-1J-2010D01*
G37*
G36*
G01X630340D02*
X627140D01*
G02Y877186I0J2010D01*
G01X630341D01*
G02X630340Y873166I-1J-2010D01*
G37*
G36*
G01X617742D02*
X614542D01*
G02Y877186I0J2010D01*
G01X617743D01*
G02X617742Y873166I-1J-2010D01*
G37*
G36*
G01X605144D02*
X601944D01*
G02Y877186I0J2010D01*
G01X605145D01*
G02X605144Y873166I-1J-2010D01*
G37*
G36*
G01X592545D02*
X589345D01*
G02Y877186I0J2010D01*
G01X592546D01*
G02X592545Y873166I-1J-2010D01*
G37*
G36*
G01X579947D02*
X576747D01*
G02Y877186I0J2010D01*
G01X579948D01*
G02X579947Y873166I-1J-2010D01*
G37*
G36*
G01X567348D02*
X564148D01*
G02Y877186I0J2010D01*
G01X567349D01*
G02X567348Y873166I-1J-2010D01*
G37*
G36*
G01X554750D02*
X551550D01*
G02Y877186I0J2010D01*
G01X554751D01*
G02X554750Y873166I-1J-2010D01*
G37*
G36*
G01X542151D02*
X538951D01*
G02Y877186I0J2010D01*
G01X542152D01*
G02X542151Y873166I-1J-2010D01*
G37*
G36*
G01X420891D02*
X417691D01*
G02Y877186I0J2010D01*
G01X420892D01*
G02X420891Y873166I-1J-2010D01*
G37*
G36*
G01X408292D02*
X405092D01*
G02Y877186I0J2010D01*
G01X408293D01*
G02X408292Y873166I-1J-2010D01*
G37*
G36*
G01X395694D02*
X392494D01*
G02Y877186I0J2010D01*
G01X395695D01*
G02X395694Y873166I-1J-2010D01*
G37*
G36*
G01X383096D02*
X379896D01*
G02Y877186I0J2010D01*
G01X383097D01*
G02X383096Y873166I-1J-2010D01*
G37*
G36*
G01X361048D02*
X357848D01*
G02Y877186I0J2010D01*
G01X361049D01*
G02X361048Y873166I-1J-2010D01*
G37*
G36*
G01X348450D02*
X345250D01*
G02Y877186I0J2010D01*
G01X348451D01*
G02X348450Y873166I-1J-2010D01*
G37*
G36*
G01X335851D02*
X332651D01*
G02Y877186I0J2010D01*
G01X335852D01*
G02X335851Y873166I-1J-2010D01*
G37*
G36*
G01X323253D02*
X320053D01*
G02Y877186I0J2010D01*
G01X323254D01*
G02X323253Y873166I-1J-2010D01*
G37*
G36*
G01X272859D02*
X269659D01*
G02Y877186I0J2010D01*
G01X272860D01*
G02X272859Y873166I-1J-2010D01*
G37*
G36*
G01X260261D02*
X257061D01*
G02Y877186I0J2010D01*
G01X260262D01*
G02X260261Y873166I-1J-2010D01*
G37*
G36*
G01X238213D02*
X235013D01*
G02Y877186I0J2010D01*
G01X238214D01*
G02X238213Y873166I-1J-2010D01*
G37*
G36*
G01X225615D02*
X222415D01*
G02Y877186I0J2010D01*
G01X225616D01*
G02X225615Y873166I-1J-2010D01*
G37*
G36*
G01X213017D02*
X209817D01*
G02Y877186I0J2010D01*
G01X213018D01*
G02X213017Y873166I-1J-2010D01*
G37*
G36*
G01X200418Y869666D02*
X197218D01*
G02Y873686I0J2010D01*
G01X200419D01*
G02X200418Y869666I-1J-2010D01*
G37*
G36*
G01X702400Y866790D02*
X699200D01*
G02Y870810I0J2010D01*
G01X702401D01*
G02X702400Y866790I-1J-2010D01*
G37*
G36*
G01X1198937Y865191D02*
Y865181D01*
X1195737Y865281D01*
Y865283D01*
X1195561Y865304D01*
G02X1195863Y869309I238J1996D01*
G01Y869319D01*
X1199062Y869219D01*
X1199071Y869210D01*
X1199145Y869205D01*
G02X1198937Y865191I-145J-2005D01*
G37*
G36*
G01X285500Y864190D02*
X282300D01*
G02Y868210I0J2010D01*
G01X285501D01*
G02X285500Y864190I-1J-2010D01*
G37*
G36*
G01X310955Y863666D02*
X307755D01*
G02Y867686I0J2010D01*
G01X310956D01*
G02X310955Y863666I-1J-2010D01*
G37*
G36*
G01X1350025Y828291D02*
X1346825D01*
G02Y832311I0J2010D01*
G01X1350026D01*
G02X1350025Y828291I-1J-2010D01*
G37*
G36*
G01X1337427D02*
X1334227D01*
G02Y832311I0J2010D01*
G01X1337428D01*
G02X1337427Y828291I-1J-2010D01*
G37*
G36*
G01X1324829D02*
X1321628D01*
G02X1321629Y832311I1J2010D01*
G01X1324829D01*
G02Y828291I0J-2010D01*
G37*
G36*
G01X1312231D02*
X1309030D01*
G02X1309031Y832311I1J2010D01*
G01X1312231D01*
G02Y828291I0J-2010D01*
G37*
G36*
G01X1287033D02*
X1283832D01*
G02X1283833Y832311I1J2010D01*
G01X1287033D01*
G02Y828291I0J-2010D01*
G37*
G36*
G01X1274435D02*
X1271234D01*
G02X1271235Y832311I1J2010D01*
G01X1274435D01*
G02Y828291I0J-2010D01*
G37*
G36*
G01X1261837D02*
X1258636D01*
G02X1258637Y832311I1J2010D01*
G01X1261837D01*
G02Y828291I0J-2010D01*
G37*
G36*
G01X1249239D02*
X1246038D01*
G02X1246039Y832311I1J2010D01*
G01X1249239D01*
G02Y828291I0J-2010D01*
G37*
G36*
G01X1236640D02*
X1233439D01*
G02X1233440Y832311I1J2010D01*
G01X1236640D01*
G02Y828291I0J-2010D01*
G37*
G36*
G01X1224042D02*
X1220842D01*
G02Y832311I0J2010D01*
G01X1224043D01*
G02X1224042Y828291I-1J-2010D01*
G37*
G36*
G01X1192545D02*
X1189344D01*
G02X1189345Y832311I1J2010D01*
G01X1192545D01*
G02Y828291I0J-2010D01*
G37*
G36*
G01X1179947D02*
X1176746D01*
G02X1176747Y832311I1J2010D01*
G01X1179947D01*
G02Y828291I0J-2010D01*
G37*
G36*
G01X1157899D02*
X1154698D01*
G02X1154699Y832311I1J2010D01*
G01X1157899D01*
G02Y828291I0J-2010D01*
G37*
G36*
G01X1145301D02*
X1142100D01*
G02X1142101Y832311I1J2010D01*
G01X1145301D01*
G02Y828291I0J-2010D01*
G37*
G36*
G01X1132703D02*
X1129503D01*
G02Y832311I0J2010D01*
G01X1132704D01*
G02X1132703Y828291I-1J-2010D01*
G37*
G36*
G01X1120104D02*
X1116903D01*
G02X1116904Y832311I1J2010D01*
G01X1120104D01*
G02Y828291I0J-2010D01*
G37*
G36*
G01X1107506D02*
X1104305D01*
G02X1104306Y832311I1J2010D01*
G01X1107506D01*
G02Y828291I0J-2010D01*
G37*
G36*
G01X1094907D02*
X1091706D01*
G02X1091707Y832311I1J2010D01*
G01X1094907D01*
G02Y828291I0J-2010D01*
G37*
G36*
G01X1082309D02*
X1079108D01*
G02X1079109Y832311I1J2010D01*
G01X1082309D01*
G02Y828291I0J-2010D01*
G37*
G36*
G01X1069711D02*
X1066510D01*
G02X1066511Y832311I1J2010D01*
G01X1069711D01*
G02Y828291I0J-2010D01*
G37*
G36*
G01X1057112D02*
X1053911D01*
G02X1053912Y832311I1J2010D01*
G01X1057112D01*
G02Y828291I0J-2010D01*
G37*
G36*
G01X1044514D02*
X1041313D01*
G02X1041314Y832311I1J2010D01*
G01X1044514D01*
G02Y828291I0J-2010D01*
G37*
G36*
G01X853962D02*
X850761D01*
G02X850762Y832311I1J2010D01*
G01X853962D01*
G02Y828291I0J-2010D01*
G37*
G36*
G01X841364D02*
X838163D01*
G02X838164Y832311I1J2010D01*
G01X841364D01*
G02Y828291I0J-2010D01*
G37*
G36*
G01X816167D02*
X812966D01*
G02X812967Y832311I1J2010D01*
G01X816167D01*
G02Y828291I0J-2010D01*
G37*
G36*
G01X803569D02*
X800368D01*
G02X800369Y832311I1J2010D01*
G01X803569D01*
G02Y828291I0J-2010D01*
G37*
G36*
G01X790970D02*
X787769D01*
G02X787770Y832311I1J2010D01*
G01X790970D01*
G02Y828291I0J-2010D01*
G37*
G36*
G01X778372D02*
X775171D01*
G02X775172Y832311I1J2010D01*
G01X778372D01*
G02Y828291I0J-2010D01*
G37*
G36*
G01X765774D02*
X762573D01*
G02X762574Y832311I1J2010D01*
G01X765774D01*
G02Y828291I0J-2010D01*
G37*
G36*
G01X753175D02*
X749974D01*
G02X749975Y832311I1J2010D01*
G01X753175D01*
G02Y828291I0J-2010D01*
G37*
G36*
G01X740577D02*
X737376D01*
G02X737377Y832311I1J2010D01*
G01X740577D01*
G02Y828291I0J-2010D01*
G37*
G36*
G01X727978D02*
X724777D01*
G02X724778Y832311I1J2010D01*
G01X727978D01*
G02Y828291I0J-2010D01*
G37*
G36*
G01X696482D02*
X693281D01*
G02X693282Y832311I1J2010D01*
G01X696482D01*
G02Y828291I0J-2010D01*
G37*
G36*
G01X683884D02*
X680683D01*
G02X680684Y832311I1J2010D01*
G01X683884D01*
G02Y828291I0J-2010D01*
G37*
G36*
G01X671285D02*
X668084D01*
G02X668085Y832311I1J2010D01*
G01X671285D01*
G02Y828291I0J-2010D01*
G37*
G36*
G01X658687D02*
X655486D01*
G02X655487Y832311I1J2010D01*
G01X658687D01*
G02Y828291I0J-2010D01*
G37*
G36*
G01X636640D02*
X633439D01*
G02X633440Y832311I1J2010D01*
G01X636640D01*
G02Y828291I0J-2010D01*
G37*
G36*
G01X624042D02*
X620841D01*
G02X620842Y832311I1J2010D01*
G01X624042D01*
G02Y828291I0J-2010D01*
G37*
G36*
G01X611443D02*
X608242D01*
G02X608243Y832311I1J2010D01*
G01X611443D01*
G02Y828291I0J-2010D01*
G37*
G36*
G01X598845D02*
X595644D01*
G02X595645Y832311I1J2010D01*
G01X598845D01*
G02Y828291I0J-2010D01*
G37*
G36*
G01X586246D02*
X583045D01*
G02X583046Y832311I1J2010D01*
G01X586246D01*
G02Y828291I0J-2010D01*
G37*
G36*
G01X573648D02*
X570447D01*
G02X570448Y832311I1J2010D01*
G01X573648D01*
G02Y828291I0J-2010D01*
G37*
G36*
G01X561050D02*
X557849D01*
G02X557850Y832311I1J2010D01*
G01X561050D01*
G02Y828291I0J-2010D01*
G37*
G36*
G01X548451D02*
X545250D01*
G02X545251Y832311I1J2010D01*
G01X548451D01*
G02Y828291I0J-2010D01*
G37*
G36*
G01X427191D02*
X423990D01*
G02X423991Y832311I1J2010D01*
G01X427191D01*
G02Y828291I0J-2010D01*
G37*
G36*
G01X414593D02*
X411392D01*
G02X411393Y832311I1J2010D01*
G01X414593D01*
G02Y828291I0J-2010D01*
G37*
G36*
G01X401994D02*
X398794D01*
G02Y832311I0J2010D01*
G01X401995D01*
G02X401994Y828291I-1J-2010D01*
G37*
G36*
G01X389396D02*
X386195D01*
G02X386196Y832311I1J2010D01*
G01X389396D01*
G02Y828291I0J-2010D01*
G37*
G36*
G01X367348D02*
X364147D01*
G02X364148Y832311I1J2010D01*
G01X367348D01*
G02Y828291I0J-2010D01*
G37*
G36*
G01X354750D02*
X351549D01*
G02X351550Y832311I1J2010D01*
G01X354750D01*
G02Y828291I0J-2010D01*
G37*
G36*
G01X342151D02*
X338950D01*
G02X338951Y832311I1J2010D01*
G01X342151D01*
G02Y828291I0J-2010D01*
G37*
G36*
G01X329553D02*
X326352D01*
G02X326353Y832311I1J2010D01*
G01X329553D01*
G02Y828291I0J-2010D01*
G37*
G36*
G01X316954D02*
X313753D01*
G02X313754Y832311I1J2010D01*
G01X316954D01*
G02Y828291I0J-2010D01*
G37*
G36*
G01X279159D02*
X275958D01*
G02X275959Y832311I1J2010D01*
G01X279159D01*
G02Y828291I0J-2010D01*
G37*
G36*
G01X266561D02*
X263360D01*
G02X263361Y832311I1J2010D01*
G01X266561D01*
G02Y828291I0J-2010D01*
G37*
G36*
G01X253962D02*
X250761D01*
G02X250762Y832311I1J2010D01*
G01X253962D01*
G02Y828291I0J-2010D01*
G37*
G36*
G01X231915D02*
X228714D01*
G02X228715Y832311I1J2010D01*
G01X231915D01*
G02Y828291I0J-2010D01*
G37*
G36*
G01X219317D02*
X216117D01*
G02Y832311I0J2010D01*
G01X219318D01*
G02X219317Y828291I-1J-2010D01*
G37*
G36*
G01X206718D02*
X203517D01*
G02X203518Y832311I1J2010D01*
G01X206718D01*
G02Y828291I0J-2010D01*
G37*
G36*
G01X194120D02*
X190919D01*
G02X190920Y832311I1J2010D01*
G01X194120D01*
G02Y828291I0J-2010D01*
G37*
G36*
G01X200620Y819691D02*
X197419D01*
G02X197420Y823711I1J2010D01*
G01X200620D01*
G02Y819691I0J-2010D01*
G37*
G36*
G01X370875Y720990D02*
X367675D01*
G02Y725010I0J2010D01*
G01X370876D01*
G02X370875Y720990I-1J-2010D01*
G37*
G36*
G01X1225348Y135950D02*
X1222148D01*
G02Y139970I0J2010D01*
G01X1225349D01*
G02X1225348Y135950I-1J-2010D01*
G37*
G36*
G01X1190835Y135889D02*
X1187635D01*
G02Y139909I0J2010D01*
G01X1190836D01*
G02X1190835Y135889I-1J-2010D01*
G37*
G36*
G01X1242900Y135841D02*
X1239700D01*
G02Y139861I0J2010D01*
G01X1242901D01*
G02X1242900Y135841I-1J-2010D01*
G37*
G36*
G01X718790Y114150D02*
Y117350D01*
G02X722810I2010J0D01*
G01Y114149D01*
G02X718790Y114150I-2010J1D01*
G37*
G36*
G01X568342Y92882D02*
X568235Y93048D01*
X568234Y93047D01*
X565281Y98559D01*
X565284Y98561D01*
X565213Y98720D01*
G02X569627Y100887I2245J1005D01*
G01X569721Y100710D01*
X569729Y100715D01*
X572588Y95380D01*
X572583Y95375D01*
X572642Y95249D01*
G02X568342Y92882I-2231J-1036D01*
G37*
G36*
G01X1170704D02*
X1170597Y93048D01*
X1170596Y93047D01*
X1167643Y98559D01*
X1167646Y98561D01*
X1167575Y98720D01*
G02X1171989Y100887I2245J1005D01*
G01X1172083Y100710D01*
X1172091Y100715D01*
X1174950Y95380D01*
X1174945Y95375D01*
X1175004Y95249D01*
G02X1170704Y92882I-2231J-1036D01*
G37*
G36*
G01X1222870D02*
X1222763Y93048D01*
X1222762Y93047D01*
X1219809Y98558D01*
X1219814Y98563D01*
X1219755Y98689D01*
G02X1224155Y100887I2231J1036D01*
G01X1224249Y100710D01*
X1224257Y100715D01*
X1227116Y95379D01*
X1227113Y95377D01*
X1227184Y95218D01*
G02X1222870Y92882I-2246J-1004D01*
G37*
G36*
G01X1188421D02*
X1188314Y93048D01*
X1188313Y93047D01*
X1185360Y98558D01*
X1185365Y98563D01*
X1185306Y98689D01*
G02X1189706Y100887I2231J1036D01*
G01X1189800Y100710D01*
X1189808Y100715D01*
X1192667Y95379D01*
X1192664Y95377D01*
X1192735Y95218D01*
G02X1188421Y92882I-2246J-1004D01*
G37*
G36*
G01X672673D02*
X672566Y93048D01*
X672565Y93047D01*
X669612Y98558D01*
X669617Y98563D01*
X669558Y98689D01*
G02X673958Y100887I2231J1036D01*
G01X674052Y100710D01*
X674060Y100715D01*
X676919Y95379D01*
X676916Y95377D01*
X676987Y95218D01*
G02X672673Y92882I-2246J-1004D01*
G37*
G36*
G01X663815D02*
X663708Y93048D01*
X663707Y93047D01*
X660754Y98558D01*
X660759Y98563D01*
X660700Y98689D01*
G02X665100Y100887I2231J1036D01*
G01X665194Y100710D01*
X665202Y100715D01*
X668061Y95379D01*
X668058Y95377D01*
X668129Y95218D01*
G02X663815Y92882I-2246J-1004D01*
G37*
G36*
G01X629366D02*
X629259Y93048D01*
X629258Y93047D01*
X626305Y98558D01*
X626310Y98563D01*
X626251Y98689D01*
G02X630651Y100887I2231J1036D01*
G01X630745Y100710D01*
X630753Y100715D01*
X633612Y95379D01*
X633609Y95377D01*
X633680Y95218D01*
G02X629366Y92882I-2246J-1004D01*
G37*
G36*
G01X620508D02*
X620401Y93048D01*
X620400Y93047D01*
X617447Y98558D01*
X617452Y98563D01*
X617393Y98689D01*
G02X621793Y100887I2231J1036D01*
G01X621887Y100710D01*
X621895Y100715D01*
X624754Y95379D01*
X624751Y95377D01*
X624822Y95218D01*
G02X620508Y92882I-2246J-1004D01*
G37*
G36*
G01X586059D02*
X585952Y93048D01*
X585951Y93047D01*
X582998Y98558D01*
X583003Y98563D01*
X582944Y98689D01*
G02X587344Y100887I2231J1036D01*
G01X587438Y100710D01*
X587446Y100715D01*
X590305Y95379D01*
X590302Y95377D01*
X590373Y95218D01*
G02X586059Y92882I-2246J-1004D01*
G37*
G36*
G01X542752D02*
X542645Y93048D01*
X542644Y93047D01*
X539691Y98558D01*
X539696Y98563D01*
X539637Y98689D01*
G02X544037Y100887I2231J1036D01*
G01X544131Y100710D01*
X544139Y100715D01*
X546998Y95379D01*
X546995Y95377D01*
X547066Y95218D01*
G02X542752Y92882I-2246J-1004D01*
G37*
G36*
G01X533793Y93052D02*
X530857Y98534D01*
X530856Y98535D01*
G02X535179Y100886I2154J1190D01*
G01X538131Y95374D01*
G02X533793Y93052I-2169J-1161D01*
G37*
G36*
G01X525035Y92882D02*
X524928Y93048D01*
X524927Y93047D01*
X521974Y98558D01*
X521979Y98563D01*
X521920Y98689D01*
G02X526320Y100887I2231J1036D01*
G01X526414Y100710D01*
X526422Y100715D01*
X529281Y95379D01*
X529278Y95377D01*
X529349Y95218D01*
G02X525035Y92882I-2246J-1004D01*
G37*
G36*
G01X1257218Y93052D02*
X1254266Y98564D01*
G02X1256412Y102185I2169J1161D01*
G02X1258604Y100886I23J-2460D01*
G01X1261540Y95404D01*
X1261541Y95403D01*
G02X1257218Y93052I-2154J-1190D01*
G37*
G36*
G01X1213911D02*
X1210959Y98564D01*
G02X1215297Y100886I2169J1161D01*
G01X1218233Y95404D01*
X1218234Y95403D01*
G02X1213911Y93052I-2154J-1190D01*
G37*
G36*
G01X654856D02*
X651904Y98564D01*
G02X656242Y100886I2169J1161D01*
G01X659178Y95404D01*
X659179Y95403D01*
G02X654856Y93052I-2154J-1190D01*
G37*
G36*
G01X611549D02*
X608597Y98564D01*
G02X612935Y100886I2169J1161D01*
G01X615871Y95404D01*
X615872Y95403D01*
G02X611549Y93052I-2154J-1190D01*
G37*
G36*
G01X718790Y93150D02*
Y96351D01*
G02X722810Y96350I2010J-1D01*
G01Y93150D01*
G02X718790I-2010J0D01*
G37*
G36*
G01X672673Y77921D02*
X672566Y78087D01*
X672565Y78086D01*
X669612Y83598D01*
X669615Y83600D01*
X669544Y83759D01*
G02X673958Y85926I2245J1005D01*
G01X674052Y85749D01*
X674060Y85754D01*
X676919Y80419D01*
X676914Y80414D01*
X676973Y80288D01*
G02X672673Y77921I-2231J-1036D01*
G37*
G36*
G01X663815D02*
X663708Y78087D01*
X663707Y78086D01*
X660754Y83598D01*
X660757Y83600D01*
X660686Y83759D01*
G02X665100Y85926I2245J1005D01*
G01X665194Y85749D01*
X665202Y85754D01*
X668061Y80419D01*
X668056Y80414D01*
X668115Y80288D01*
G02X663815Y77921I-2231J-1036D01*
G37*
G36*
G01X586059D02*
X585952Y78087D01*
X585951Y78086D01*
X582998Y83598D01*
X583001Y83600D01*
X582930Y83759D01*
G02X587344Y85926I2245J1005D01*
G01X587438Y85749D01*
X587446Y85754D01*
X590305Y80419D01*
X590300Y80414D01*
X590359Y80288D01*
G02X586059Y77921I-2231J-1036D01*
G37*
G36*
G01X1188421D02*
X1188314Y78087D01*
X1188313Y78086D01*
X1185360Y83598D01*
X1185363Y83600D01*
X1185292Y83759D01*
G02X1189706Y85926I2245J1005D01*
G01X1189800Y85749D01*
X1189808Y85754D01*
X1192667Y80419D01*
X1192662Y80414D01*
X1192721Y80288D01*
G02X1188421Y77921I-2231J-1036D01*
G37*
G36*
G01X1145114D02*
X1145007Y78087D01*
X1145006Y78086D01*
X1142053Y83597D01*
X1142058Y83602D01*
X1141999Y83728D01*
G02X1146399Y85926I2231J1036D01*
G01X1146493Y85749D01*
X1146501Y85754D01*
X1149360Y80418D01*
X1149357Y80416D01*
X1149428Y80257D01*
G02X1145114Y77921I-2246J-1004D01*
G37*
G36*
G01X533793Y78091D02*
X530857Y83573D01*
X530856Y83574D01*
G02X535179Y85925I2154J1190D01*
G01X538131Y80413D01*
G02X533793Y78091I-2169J-1161D01*
G37*
G36*
G01X1179462D02*
X1176510Y83603D01*
G02X1180848Y85925I2169J1161D01*
G01X1183784Y80443D01*
X1183785Y80442D01*
G02X1179462Y78091I-2154J-1190D01*
G37*
G36*
G01X1101339Y70669D02*
X1101290Y73869D01*
G02X1105310Y73931I2010J31D01*
G01X1105359Y70732D01*
G02X1101339Y70669I-2010J-32D01*
G37*
G36*
G01X1170704Y48000D02*
X1170597Y48166D01*
X1170596Y48165D01*
X1167643Y53676D01*
X1167648Y53681D01*
X1167589Y53807D01*
G02X1171989Y56005I2231J1036D01*
G01X1172083Y55828D01*
X1172091Y55833D01*
X1174950Y50497D01*
X1174947Y50495D01*
X1175018Y50336D01*
G02X1170704Y48000I-2246J-1004D01*
G37*
G36*
G01X568342D02*
X568235Y48166D01*
X568234Y48165D01*
X565281Y53676D01*
X565286Y53681D01*
X565227Y53807D01*
G02X569627Y56005I2231J1036D01*
G01X569721Y55828D01*
X569729Y55833D01*
X572588Y50497D01*
X572585Y50495D01*
X572656Y50336D01*
G02X568342Y48000I-2246J-1004D01*
G37*
G36*
G01X1292817Y139490D02*
X1296018D01*
G02X1296017Y135466I-1J-2012D01*
G01X1292817D01*
G02Y139490I0J2012D01*
G37*
G36*
G01X1283343Y143592D02*
X1286544D01*
G02X1286543Y139570I-1J-2011D01*
G01X1283343D01*
G02Y143592I0J2011D01*
G37*
G36*
G01X1261944Y143758D02*
X1258743D01*
G02X1258744Y147782I1J2012D01*
G01X1261944D01*
G02Y143758I0J-2012D01*
G37*
G36*
G01X1277265Y135662D02*
X1274064D01*
G02X1274065Y139684I1J2011D01*
G01X1277265D01*
G02Y135662I0J-2011D01*
G37*
G36*
G01X1266177Y92880D02*
X1266070Y93046D01*
X1266068Y93045D01*
X1263114Y98558D01*
X1263119Y98563D01*
X1263060Y98690D01*
G02X1267463Y100888I2233J1035D01*
G01X1267557Y100712D01*
X1267565Y100716D01*
X1270425Y95378D01*
X1270422Y95377D01*
X1270493Y95218D01*
G02X1266177Y92880I-2248J-1004D01*
G37*
G36*
G01Y77919D02*
X1266070Y78085D01*
X1266068Y78084D01*
X1263114Y83599D01*
X1263117Y83600D01*
X1263046Y83759D01*
G02X1267463Y85927I2247J1006D01*
G01X1267557Y85751D01*
X1267565Y85755D01*
X1270425Y80419D01*
X1270420Y80414D01*
X1270479Y80287D01*
G02X1266177Y77919I-2234J-1034D01*
G37*
G36*
G01X1275035D02*
X1274928Y78085D01*
X1274926Y78084D01*
X1271972Y83599D01*
X1271975Y83600D01*
X1271904Y83759D01*
G02X1276321Y85927I2247J1006D01*
G01X1276415Y85751D01*
X1276423Y85755D01*
X1279283Y80419D01*
X1279278Y80414D01*
X1279337Y80287D01*
G02X1275035Y77919I-2234J-1034D01*
G37*
G36*
G01Y92880D02*
X1274928Y93046D01*
X1274926Y93045D01*
X1271972Y98558D01*
X1271977Y98563D01*
X1271918Y98690D01*
G02X1276321Y100888I2233J1035D01*
G01X1276415Y100712D01*
X1276423Y100716D01*
X1279283Y95378D01*
X1279280Y95377D01*
X1279351Y95218D01*
G02X1275035Y92880I-2248J-1004D01*
G37*
G36*
G01X1258605Y56005D02*
X1261557Y50493D01*
G02X1257217Y48169I-2170J-1162D01*
G01X1254281Y53651D01*
X1254280Y53652D01*
G02X1258605Y56005I2155J1191D01*
G37*
G36*
G01X1275035Y47998D02*
X1274928Y48164D01*
X1274926Y48163D01*
X1271972Y53676D01*
X1271977Y53681D01*
X1271918Y53808D01*
G02X1276321Y56006I2233J1035D01*
G01X1276415Y55830D01*
X1276423Y55834D01*
X1279283Y50496D01*
X1279280Y50495D01*
X1279351Y50336D01*
G02X1275035Y47998I-2248J-1004D01*
G37*
G36*
G01X1266177D02*
X1266070Y48164D01*
X1266068Y48163D01*
X1263114Y53676D01*
X1263119Y53681D01*
X1263060Y53808D01*
G02X1267463Y56006I2233J1035D01*
G01X1267557Y55830D01*
X1267565Y55834D01*
X1270425Y50496D01*
X1270422Y50495D01*
X1270493Y50336D01*
G02X1266177Y47998I-2248J-1004D01*
G37*
G36*
G01X1275030Y62966D02*
X1274929Y63124D01*
X1274926Y63123D01*
X1271972Y68636D01*
X1271977Y68641D01*
X1271918Y68768D01*
G02X1276320Y70967I2233J1035D01*
G01X1276414Y70791D01*
X1276423Y70796D01*
X1279283Y65458D01*
X1279280Y65457D01*
X1279354Y65290D01*
G02X1275030Y62966I-2250J-999D01*
G37*
G36*
G01X1266172D02*
X1266071Y63124D01*
X1266068Y63123D01*
X1263114Y68636D01*
X1263119Y68641D01*
X1263060Y68768D01*
G02X1267462Y70967I2233J1035D01*
G01X1267556Y70791D01*
X1267565Y70796D01*
X1270425Y65458D01*
X1270422Y65457D01*
X1270496Y65290D01*
G02X1266172Y62966I-2250J-999D01*
G37*
G36*
G01X1234209Y140452D02*
X1231008D01*
G02X1231009Y144474I1J2011D01*
G01X1234209D01*
G02Y140452I0J-2011D01*
G37*
G36*
G01X1222870Y77919D02*
X1222763Y78085D01*
X1222761Y78084D01*
X1219807Y83599D01*
X1219810Y83600D01*
X1219739Y83759D01*
G02X1224156Y85927I2247J1006D01*
G01X1224250Y85751D01*
X1224258Y85755D01*
X1227118Y80419D01*
X1227113Y80414D01*
X1227172Y80287D01*
G02X1222870Y77919I-2234J-1034D01*
G37*
G36*
G01X1231728Y92880D02*
X1231621Y93046D01*
X1231619Y93045D01*
X1228665Y98558D01*
X1228670Y98563D01*
X1228611Y98690D01*
G02X1233014Y100888I2233J1035D01*
G01X1233108Y100712D01*
X1233116Y100716D01*
X1235976Y95378D01*
X1235973Y95377D01*
X1236044Y95218D01*
G02X1231728Y92880I-2248J-1004D01*
G37*
G36*
G01Y77919D02*
X1231621Y78085D01*
X1231619Y78084D01*
X1228665Y83599D01*
X1228668Y83600D01*
X1228597Y83759D01*
G02X1233014Y85927I2247J1006D01*
G01X1233108Y85751D01*
X1233116Y85755D01*
X1235976Y80419D01*
X1235971Y80414D01*
X1236030Y80287D01*
G02X1231728Y77919I-2234J-1034D01*
G37*
G36*
G01Y47998D02*
X1231621Y48164D01*
X1231619Y48163D01*
X1228665Y53676D01*
X1228670Y53681D01*
X1228611Y53808D01*
G02X1233014Y56006I2233J1035D01*
G01X1233108Y55830D01*
X1233116Y55834D01*
X1235976Y50496D01*
X1235973Y50495D01*
X1236044Y50336D01*
G02X1231728Y47998I-2248J-1004D01*
G37*
G36*
G01X1222870D02*
X1222763Y48164D01*
X1222761Y48163D01*
X1219807Y53676D01*
X1219812Y53681D01*
X1219753Y53808D01*
G02X1224156Y56006I2233J1035D01*
G01X1224250Y55830D01*
X1224258Y55834D01*
X1227118Y50496D01*
X1227115Y50495D01*
X1227186Y50336D01*
G02X1222870Y47998I-2248J-1004D01*
G37*
G36*
G01X1231723Y62966D02*
X1231622Y63124D01*
X1231619Y63123D01*
X1228665Y68636D01*
X1228670Y68641D01*
X1228611Y68768D01*
G02X1233013Y70967I2233J1035D01*
G01X1233107Y70791D01*
X1233116Y70796D01*
X1235976Y65458D01*
X1235973Y65457D01*
X1236047Y65290D01*
G02X1231723Y62966I-2250J-999D01*
G37*
G36*
G01X1222865D02*
X1222764Y63124D01*
X1222761Y63123D01*
X1219807Y68636D01*
X1219812Y68641D01*
X1219753Y68768D01*
G02X1224155Y70967I2233J1035D01*
G01X1224249Y70791D01*
X1224258Y70796D01*
X1227118Y65458D01*
X1227115Y65457D01*
X1227189Y65290D01*
G02X1222865Y62966I-2250J-999D01*
G37*
G36*
G01X1203791Y158742D02*
X1206992D01*
G02X1206991Y154718I-1J-2012D01*
G01X1203791D01*
G02Y158742I0J2012D01*
G37*
G36*
G01X1196200Y144862D02*
X1199401D01*
G02X1199400Y140840I-1J-2011D01*
G01X1196200D01*
G02Y144862I0J2011D01*
G37*
G36*
G01X1215298Y56005D02*
X1218250Y50493D01*
G02X1213910Y48169I-2170J-1162D01*
G01X1210974Y53651D01*
X1210973Y53652D01*
G02X1215298Y56005I2155J1191D01*
G37*
G36*
G01X1188421Y47998D02*
X1188314Y48164D01*
X1188312Y48163D01*
X1185358Y53676D01*
X1185363Y53681D01*
X1185304Y53808D01*
G02X1189707Y56006I2233J1035D01*
G01X1189801Y55830D01*
X1189809Y55834D01*
X1192669Y50496D01*
X1192666Y50495D01*
X1192737Y50336D01*
G02X1188421Y47998I-2248J-1004D01*
G37*
G36*
G01X1188416Y62966D02*
X1188315Y63124D01*
X1188312Y63123D01*
X1185358Y68636D01*
X1185363Y68641D01*
X1185304Y68768D01*
G02X1189706Y70967I2233J1035D01*
G01X1189800Y70791D01*
X1189809Y70796D01*
X1192669Y65458D01*
X1192666Y65457D01*
X1192740Y65290D01*
G02X1188416Y62966I-2250J-999D01*
G37*
G36*
G01X1182061Y140466D02*
X1178860D01*
G02X1178861Y144490I1J2012D01*
G01X1182061D01*
G02Y140466I0J-2012D01*
G37*
G36*
G01X1180849Y100887D02*
X1183801Y95375D01*
G02X1179461Y93051I-2170J-1162D01*
G01X1176525Y98533D01*
X1176524Y98534D01*
G02X1180849Y100887I2155J1191D01*
G37*
G36*
G01Y56005D02*
X1183801Y50493D01*
G02X1179461Y48169I-2170J-1162D01*
G01X1176525Y53651D01*
X1176524Y53652D01*
G02X1180849Y56005I2155J1191D01*
G37*
G36*
G01X1179562Y62959D02*
X1179455Y63125D01*
X1179453Y63124D01*
X1176500Y68636D01*
X1176505Y68641D01*
X1176446Y68768D01*
G02X1180849Y70966I2233J1035D01*
G01X1180943Y70790D01*
X1180951Y70794D01*
X1183810Y65457D01*
X1183807Y65456D01*
X1183878Y65297D01*
G02X1179562Y62959I-2248J-1004D01*
G37*
G36*
G01X1127397Y92880D02*
X1127290Y93046D01*
X1127288Y93045D01*
X1124334Y98558D01*
X1124339Y98563D01*
X1124280Y98690D01*
G02X1128683Y100888I2233J1035D01*
G01X1128777Y100712D01*
X1128785Y100716D01*
X1131645Y95378D01*
X1131642Y95377D01*
X1131713Y95218D01*
G02X1127397Y92880I-2248J-1004D01*
G37*
G36*
G01X1137542Y100887D02*
X1140494Y95375D01*
G02X1136154Y93051I-2170J-1162D01*
G01X1133218Y98533D01*
X1133217Y98534D01*
G02X1137542Y100887I2155J1191D01*
G37*
G36*
G01X1111088Y81902D02*
X1111198Y82050D01*
X1111197Y82052D01*
X1113341Y84432D01*
X1113343Y84430D01*
X1113475Y84553D01*
G02X1116337Y81733I1367J-1475D01*
G01X1116203Y81585D01*
X1116211Y81578D01*
X1114203Y79348D01*
X1114192D01*
X1114133Y79288D01*
G02X1111088Y81902I-1432J1412D01*
G37*
G36*
G01X1145114Y92880D02*
X1145007Y93046D01*
X1145005Y93045D01*
X1142051Y98558D01*
X1142056Y98563D01*
X1141997Y98690D01*
G02X1146400Y100888I2233J1035D01*
G01X1146494Y100712D01*
X1146502Y100716D01*
X1149362Y95378D01*
X1149359Y95377D01*
X1149430Y95218D01*
G02X1145114Y92880I-2248J-1004D01*
G37*
G36*
G01X1137542Y85926D02*
X1140494Y80414D01*
G02X1136154Y78090I-2170J-1162D01*
G01X1133218Y83572D01*
X1133217Y83573D01*
G02X1137542Y85926I2155J1191D01*
G37*
G36*
G01X1127397Y47998D02*
X1127290Y48164D01*
X1127288Y48163D01*
X1124334Y53678D01*
X1124337Y53679D01*
X1124266Y53838D01*
G02X1128683Y56006I2247J1006D01*
G01X1128777Y55830D01*
X1128785Y55834D01*
X1131645Y50498D01*
X1131640Y50493D01*
X1131699Y50366D01*
G02X1127397Y47998I-2234J-1034D01*
G37*
G36*
G01X1145114D02*
X1145007Y48164D01*
X1145005Y48163D01*
X1142051Y53678D01*
X1142054Y53679D01*
X1141983Y53838D01*
G02X1146400Y56006I2247J1006D01*
G01X1146494Y55830D01*
X1146502Y55834D01*
X1149362Y50498D01*
X1149357Y50493D01*
X1149416Y50366D01*
G02X1145114Y47998I-2234J-1034D01*
G37*
G36*
G01X1137542Y56005D02*
X1140478Y50523D01*
X1140479Y50522D01*
G02X1136154Y48169I-2155J-1191D01*
G01X1133202Y53681D01*
G02X1137542Y56005I2170J1162D01*
G37*
G36*
G01X1145109Y62966D02*
X1145008Y63124D01*
X1145005Y63123D01*
X1142051Y68636D01*
X1142056Y68641D01*
X1141997Y68768D01*
G02X1146399Y70967I2233J1035D01*
G01X1146493Y70791D01*
X1146502Y70796D01*
X1149362Y65458D01*
X1149359Y65457D01*
X1149433Y65290D01*
G02X1145109Y62966I-2250J-999D01*
G37*
G36*
G01X1136255Y62959D02*
X1136148Y63125D01*
X1136146Y63124D01*
X1133193Y68636D01*
X1133198Y68641D01*
X1133139Y68768D01*
G02X1137542Y70966I2233J1035D01*
G01X1137636Y70790D01*
X1137644Y70794D01*
X1140503Y65457D01*
X1140500Y65456D01*
X1140571Y65297D01*
G02X1136255Y62959I-2248J-1004D01*
G37*
G36*
G01X1069124Y57175D02*
Y60376D01*
G02X1073146Y60375I2011J-1D01*
G01Y57175D01*
G02X1069124I-2011J0D01*
G37*
G36*
G01X1059012Y57700D02*
Y54499D01*
G02X1054988Y54500I-2012J1D01*
G01Y57700D01*
G02X1059012I2012J0D01*
G37*
G36*
G01X1063212Y24088D02*
Y20887D01*
G02X1059188Y20888I-2012J1D01*
G01Y24088D01*
G02X1063212I2012J0D01*
G37*
G36*
G01X1067712Y36088D02*
Y32887D01*
G02X1063688Y32888I-2012J1D01*
G01Y36088D01*
G02X1067712I2012J0D01*
G37*
G36*
G01X722812Y81350D02*
Y78149D01*
G02X718788Y78150I-2012J1D01*
G01Y81350D01*
G02X722812I2012J0D01*
G37*
G36*
G01X734512Y101621D02*
Y98420D01*
G02X730488Y98421I-2012J1D01*
G01Y101621D01*
G02X734512I2012J0D01*
G37*
G36*
G01X722812Y105350D02*
Y102149D01*
G02X718788Y102150I-2012J1D01*
G01Y105350D01*
G02X722812I2012J0D01*
G37*
G36*
G01X728620Y49251D02*
Y46050D01*
G02X724598Y46051I-2011J1D01*
G01Y49251D01*
G02X728620I2011J0D01*
G37*
G36*
G01X722955Y35106D02*
X726156D01*
G02X726155Y31084I-1J-2011D01*
G01X722955D01*
G02Y35106I0J2011D01*
G37*
G36*
G01X683600Y376706D02*
X680099D01*
G02X680100Y380730I1J2012D01*
G01X683600D01*
G02Y376706I0J-2012D01*
G37*
G36*
G01X662256Y352200D02*
Y348999D01*
G02X658232Y349000I-2012J1D01*
G01Y352200D01*
G02X662256I2012J0D01*
G37*
G36*
G01X640550Y323512D02*
X643751D01*
G02X643750Y319488I-1J-2012D01*
G01X640550D01*
G02Y323512I0J2012D01*
G37*
G36*
G01X656243Y56005D02*
X659195Y50493D01*
G02X654855Y48169I-2170J-1162D01*
G01X651919Y53651D01*
X651918Y53652D01*
G02X656243Y56005I2155J1191D01*
G37*
G36*
G01X663815Y47998D02*
X663708Y48164D01*
X663706Y48163D01*
X660752Y53676D01*
X660757Y53681D01*
X660698Y53808D01*
G02X665101Y56006I2233J1035D01*
G01X665195Y55830D01*
X665203Y55834D01*
X668063Y50496D01*
X668060Y50495D01*
X668131Y50336D01*
G02X663815Y47998I-2248J-1004D01*
G37*
G36*
G01X663810Y62966D02*
X663709Y63124D01*
X663706Y63123D01*
X660752Y68636D01*
X660757Y68641D01*
X660698Y68768D01*
G02X665100Y70967I2233J1035D01*
G01X665194Y70791D01*
X665203Y70796D01*
X668063Y65458D01*
X668060Y65457D01*
X668134Y65290D01*
G02X663810Y62966I-2250J-999D01*
G37*
G36*
G01X672668D02*
X672567Y63124D01*
X672564Y63123D01*
X669610Y68636D01*
X669615Y68641D01*
X669556Y68768D01*
G02X673958Y70967I2233J1035D01*
G01X674052Y70791D01*
X674061Y70796D01*
X676921Y65458D01*
X676918Y65457D01*
X676992Y65290D01*
G02X672668Y62966I-2250J-999D01*
G37*
G36*
G01X672673Y47998D02*
X672566Y48164D01*
X672564Y48163D01*
X669610Y53676D01*
X669615Y53681D01*
X669556Y53808D01*
G02X673959Y56006I2233J1035D01*
G01X674053Y55830D01*
X674061Y55834D01*
X676921Y50496D01*
X676918Y50495D01*
X676989Y50336D01*
G02X672673Y47998I-2248J-1004D01*
G37*
G36*
G01X636950Y151662D02*
X640151D01*
G02X640150Y147638I-1J-2012D01*
G01X636950D01*
G02Y151662I0J2012D01*
G37*
G36*
G01X638150Y135868D02*
X634949D01*
G02X634950Y139892I1J2012D01*
G01X638150D01*
G02Y135868I0J-2012D01*
G37*
G36*
G01X627826D02*
X624625D01*
G02X624626Y139892I1J2012D01*
G01X627826D01*
G02Y135868I0J-2012D01*
G37*
G36*
G01X629366Y77919D02*
X629259Y78085D01*
X629257Y78084D01*
X626303Y83599D01*
X626306Y83600D01*
X626235Y83759D01*
G02X630652Y85927I2247J1006D01*
G01X630746Y85751D01*
X630754Y85755D01*
X633614Y80419D01*
X633609Y80414D01*
X633668Y80287D01*
G02X629366Y77919I-2234J-1034D01*
G37*
G36*
G01X612936Y56005D02*
X615888Y50493D01*
G02X611548Y48169I-2170J-1162D01*
G01X608612Y53651D01*
X608611Y53652D01*
G02X612936Y56005I2155J1191D01*
G37*
G36*
G01X629361Y62966D02*
X629260Y63124D01*
X629257Y63123D01*
X626303Y68636D01*
X626308Y68641D01*
X626249Y68768D01*
G02X630651Y70967I2233J1035D01*
G01X630745Y70791D01*
X630754Y70796D01*
X633614Y65458D01*
X633611Y65457D01*
X633685Y65290D01*
G02X629361Y62966I-2250J-999D01*
G37*
G36*
G01X620503D02*
X620402Y63124D01*
X620399Y63123D01*
X617445Y68636D01*
X617450Y68641D01*
X617391Y68768D01*
G02X621793Y70967I2233J1035D01*
G01X621887Y70791D01*
X621896Y70796D01*
X624756Y65458D01*
X624753Y65457D01*
X624827Y65290D01*
G02X620503Y62966I-2250J-999D01*
G37*
G36*
G01X620508Y47998D02*
X620401Y48164D01*
X620399Y48163D01*
X617445Y53676D01*
X617450Y53681D01*
X617391Y53808D01*
G02X621794Y56006I2233J1035D01*
G01X621888Y55830D01*
X621896Y55834D01*
X624756Y50496D01*
X624753Y50495D01*
X624824Y50336D01*
G02X620508Y47998I-2248J-1004D01*
G37*
G36*
G01X629366D02*
X629259Y48164D01*
X629257Y48163D01*
X626303Y53676D01*
X626308Y53681D01*
X626249Y53808D01*
G02X630652Y56006I2233J1035D01*
G01X630746Y55830D01*
X630754Y55834D01*
X633614Y50496D01*
X633611Y50495D01*
X633682Y50336D01*
G02X629366Y47998I-2248J-1004D01*
G37*
G36*
G01X594150Y151962D02*
X597351D01*
G02X597350Y147938I-1J-2012D01*
G01X594150D01*
G02Y151962I0J2012D01*
G37*
G36*
G01X601250Y139792D02*
X604451D01*
G02X604450Y135768I-1J-2012D01*
G01X601250D01*
G02Y139792I0J2012D01*
G37*
G36*
G01X584650Y139812D02*
X587851D01*
G02X587850Y135788I-1J-2012D01*
G01X584650D01*
G02Y139812I0J2012D01*
G37*
G36*
G01X577650Y135768D02*
X574449D01*
G02X574450Y139792I1J2012D01*
G01X577650D01*
G02Y135768I0J-2012D01*
G37*
G36*
G01X578487Y85926D02*
X581423Y80444D01*
X581424Y80443D01*
G02X577099Y78090I-2155J-1191D01*
G01X574147Y83602D01*
G02X578487Y85926I2170J1162D01*
G37*
G36*
G01X577099Y93051D02*
X574163Y98533D01*
X574162Y98534D01*
G02X578487Y100887I2155J1191D01*
G01X581439Y95375D01*
G02X577099Y93051I-2170J-1162D01*
G37*
G36*
G01X586054Y62966D02*
X585953Y63124D01*
X585950Y63123D01*
X582996Y68636D01*
X583001Y68641D01*
X582942Y68768D01*
G02X587344Y70967I2233J1035D01*
G01X587438Y70791D01*
X587447Y70796D01*
X590307Y65458D01*
X590304Y65457D01*
X590378Y65290D01*
G02X586054Y62966I-2250J-999D01*
G37*
G36*
G01X577200Y62959D02*
X577093Y63125D01*
X577091Y63124D01*
X574138Y68636D01*
X574143Y68641D01*
X574084Y68768D01*
G02X578487Y70966I2233J1035D01*
G01X578581Y70790D01*
X578589Y70794D01*
X581448Y65457D01*
X581445Y65456D01*
X581516Y65297D01*
G02X577200Y62959I-2248J-1004D01*
G37*
G36*
G01X586059Y47998D02*
X585952Y48164D01*
X585950Y48163D01*
X582996Y53676D01*
X583001Y53681D01*
X582942Y53808D01*
G02X587345Y56006I2233J1035D01*
G01X587439Y55830D01*
X587447Y55834D01*
X590307Y50496D01*
X590304Y50495D01*
X590375Y50336D01*
G02X586059Y47998I-2248J-1004D01*
G37*
G36*
G01X578487Y56005D02*
X581439Y50493D01*
G02X577099Y48169I-2170J-1162D01*
G01X574163Y53651D01*
X574162Y53652D01*
G02X578487Y56005I2155J1191D01*
G37*
G36*
G01X548700Y150188D02*
X545499D01*
G02X545500Y154212I1J2012D01*
G01X548700D01*
G02Y150188I0J-2012D01*
G37*
G36*
G01X541600Y139780D02*
X544801D01*
G02X544800Y135758I-1J-2011D01*
G01X541600D01*
G02Y139780I0J2011D01*
G37*
G36*
G01X542752Y47998D02*
X542645Y48164D01*
X542643Y48163D01*
X539689Y53678D01*
X539692Y53679D01*
X539621Y53838D01*
G02X544038Y56006I2247J1006D01*
G01X544132Y55830D01*
X544140Y55834D01*
X547000Y50498D01*
X546995Y50493D01*
X547054Y50366D01*
G02X542752Y47998I-2234J-1034D01*
G37*
G36*
G01X542747Y62966D02*
X542646Y63124D01*
X542643Y63123D01*
X539689Y68636D01*
X539694Y68641D01*
X539635Y68768D01*
G02X544037Y70967I2233J1035D01*
G01X544131Y70791D01*
X544140Y70796D01*
X547000Y65458D01*
X546997Y65457D01*
X547071Y65290D01*
G02X542747Y62966I-2250J-999D01*
G37*
G36*
G01X521098Y168200D02*
Y163799D01*
G02X516274Y163800I-2412J1D01*
G01Y168200D01*
G02X521098I2412J0D01*
G37*
G36*
G01X526977Y142720D02*
X530178D01*
G02X530177Y138696I-1J-2012D01*
G01X526977D01*
G02Y142720I0J2012D01*
G37*
G36*
G01X519300Y136860D02*
X516099D01*
G02X516100Y140882I1J2011D01*
G01X519300D01*
G02Y136860I0J-2011D01*
G37*
G36*
G01X525035Y47998D02*
X524928Y48164D01*
X524926Y48163D01*
X521972Y53678D01*
X521975Y53679D01*
X521904Y53838D01*
G02X526321Y56006I2247J1006D01*
G01X526415Y55830D01*
X526423Y55834D01*
X529283Y50498D01*
X529278Y50493D01*
X529337Y50366D01*
G02X525035Y47998I-2234J-1034D01*
G37*
G36*
G01X535180Y56005D02*
X538116Y50523D01*
X538117Y50522D01*
G02X533792Y48169I-2155J-1191D01*
G01X530840Y53681D01*
G02X535180Y56005I2170J1162D01*
G37*
G36*
G01X533893Y62959D02*
X533786Y63125D01*
X533784Y63124D01*
X530831Y68636D01*
X530836Y68641D01*
X530777Y68768D01*
G02X535180Y70966I2233J1035D01*
G01X535274Y70790D01*
X535282Y70794D01*
X538141Y65457D01*
X538138Y65456D01*
X538209Y65297D01*
G02X533893Y62959I-2248J-1004D01*
G37*
G36*
G01X406452Y323300D02*
Y318899D01*
G02X401628Y318900I-2412J1D01*
G01Y323300D01*
G02X406452I2412J0D01*
G37*
G36*
G01X401588Y142542D02*
Y146043D01*
G02X405612Y146042I2012J-1D01*
G01Y142542D01*
G02X401588I-2012J0D01*
G37*
G36*
G01X403312Y156715D02*
Y153214D01*
G02X399288Y153215I-2012J1D01*
G01Y156715D01*
G02X403312I2012J0D01*
G37*
G36*
G01X360545Y730825D02*
X360662Y730965D01*
X360661Y730966D01*
X362924Y733230D01*
X362937D01*
X362995Y733283D01*
G02X365900Y730514I1360J-1482D01*
G01X365783Y730374D01*
X365784Y730373D01*
X363519Y728108D01*
X363518Y728109D01*
X363378Y727992D01*
G02X360545Y730825I-1287J1546D01*
G37*
G36*
G01X339640Y301534D02*
Y305035D01*
G02X343664Y305034I2012J-1D01*
G01Y301534D01*
G02X339640I-2012J0D01*
G37*
G36*
G01X370914Y40157D02*
G02X365945Y35188I-4969J0D01*
G01X356102D01*
G02X351132Y40157I0J4970D01*
G01Y71654D01*
G02X356102Y76624I4970J0D01*
G01X365945D01*
G02X370914Y71654I-1J-4970D01*
G01Y40157D01*
G37*
G36*
G01X260407Y500662D02*
X257206D01*
G02X257207Y504686I1J2012D01*
G01X260407D01*
G02Y500662I0J-2012D01*
G37*
G36*
G01X231750Y770688D02*
X228549D01*
G02X228550Y774712I1J2012D01*
G01X231750D01*
G02Y770688I0J-2012D01*
G37*
G36*
G01X223872Y339875D02*
Y335474D01*
G02X219048Y335475I-2412J1D01*
G01Y339875D01*
G02X223872I2412J0D01*
G37*
G36*
G01X209866Y186480D02*
X206296D01*
G02X206297Y190504I1J2012D01*
G01X209866D01*
G02Y186480I0J-2012D01*
G37*
G36*
G01X105282Y565740D02*
Y561339D01*
G02X100458Y561340I-2412J1D01*
G01Y565740D01*
G02X105282I2412J0D01*
G37*
G36*
G01X93612Y453200D02*
Y448799D01*
G02X88788Y448800I-2412J1D01*
G01Y453200D01*
G02X93612I2412J0D01*
G37*
G36*
G01X93940Y438600D02*
Y443001D01*
G02X98762Y443000I2411J-1D01*
G01Y438600D01*
G02X93940I-2411J0D01*
G37*
G36*
G01X83500Y342188D02*
X80299D01*
G02X80300Y346212I1J2012D01*
G01X83500D01*
G02Y342188I0J-2012D01*
G37*
G36*
G01X77421Y320458D02*
X74220D01*
G02X74221Y324482I1J2012D01*
G01X77421D01*
G02Y320458I0J-2012D01*
G37*
G36*
G01X76325Y286220D02*
X73124D01*
G02X73125Y290242I1J2011D01*
G01X76325D01*
G02Y286220I0J-2011D01*
G37*
G36*
G01X74200Y218540D02*
X77401D01*
G02X77400Y214516I-1J-2012D01*
G01X74200D01*
G02Y218540I0J2012D01*
G37*
G36*
G01X92000Y208840D02*
X88799D01*
G02X88800Y212862I1J2011D01*
G01X92000D01*
G02Y208840I0J-2011D01*
G37*
G36*
G01X65400Y286244D02*
X62199D01*
G02X62200Y290268I1J2012D01*
G01X65400D01*
G02Y286244I0J-2012D01*
G37*
G36*
G01X65712Y263925D02*
Y260724D01*
G02X61688Y260725I-2012J1D01*
G01Y263925D01*
G02X65712I2012J0D01*
G37*
G36*
G01X57812Y269493D02*
Y266292D01*
G02X53788Y266293I-2012J1D01*
G01Y269493D01*
G02X57812I2012J0D01*
G37*
G36*
G01X56600Y209916D02*
X53399D01*
G02X53400Y213940I1J2012D01*
G01X56600D01*
G02Y209916I0J-2012D01*
G37*
G36*
G01X38050Y218740D02*
X41251D01*
G02X41250Y214716I-1J-2012D01*
G01X38050D01*
G02Y218740I0J2012D01*
G37*
G36*
G01X1162654Y139999D02*
G02X1161307Y136494I-1347J-1494D01*
G01X1158554D01*
X1124311Y102250D01*
X951575D01*
X951522Y102129D01*
G02X950891Y101293I-2023J870D01*
G03X950861Y100700I253J-310D01*
G01X991350Y60211D01*
Y51783D01*
X991473Y51731D01*
G02Y47665I-845J-2033D01*
G01X991350Y47613D01*
Y38789D01*
X987711Y35150D01*
X926811D01*
X924011Y32350D01*
X921387D01*
G02X917413I-1987J950D01*
G01X872989D01*
X860789Y44550D01*
X856989D01*
X851560Y49979D01*
X851497Y49990D01*
G02X849700Y51787I373J2170D01*
G01X849689Y51850D01*
X843850Y57689D01*
Y80411D01*
X846089Y82650D01*
X900078Y82627D01*
X903072Y85621D01*
Y128215D01*
X901947Y129340D01*
X892679D01*
X891324Y130695D01*
Y155435D01*
X890509Y156250D01*
X772189D01*
X761395Y167044D01*
X761309Y167041D01*
G02X759041Y169309I-67J2201D01*
G01X759044Y169395D01*
X739250Y189189D01*
Y216311D01*
X744310Y221371D01*
Y224129D01*
X737189Y231250D01*
X735918D01*
X735899Y231246D01*
G02X734901I-499J2554D01*
G01X734882Y231250D01*
X730918D01*
X730899Y231246D01*
G02X729901I-499J2554D01*
G01X729882Y231250D01*
X726418D01*
X726399Y231246D01*
G02X725401I-499J2554D01*
G01X725382Y231250D01*
X721918D01*
X721899Y231246D01*
G02X720901I-499J2554D01*
G01X720882Y231250D01*
X717418D01*
X717399Y231246D01*
G02X716401I-499J2554D01*
G01X716382Y231250D01*
X712918D01*
X712899Y231246D01*
G02X711901I-499J2554D01*
G01X711882Y231250D01*
X708418D01*
X708399Y231246D01*
G02X707401I-499J2554D01*
G01X707382Y231250D01*
X705689D01*
X705251Y231688D01*
G02X701486Y235217I-1651J2011D01*
G01X701585Y235354D01*
X700750Y236189D01*
Y240194D01*
X698694Y242250D01*
X645189D01*
X640750Y246689D01*
Y278311D01*
X642689Y280250D01*
X673638D01*
X675750Y282362D01*
Y297618D01*
G02Y302182I1250J2282D01*
G01Y312811D01*
X703689Y340750D01*
X931311D01*
X972250Y299811D01*
Y292812D01*
X974312Y290750D01*
X1217811D01*
X1221750Y286811D01*
Y272362D01*
X1223862Y270250D01*
X1280811D01*
X1283250Y267811D01*
Y219689D01*
X1279311Y215750D01*
X1223728D01*
X1221750Y213772D01*
Y199689D01*
X1162639Y140579D01*
G03X1162654Y139999I283J-283D01*
G37*
G54D54*
X1027722Y-9125D03*
X1054494D03*
G54D53*
X988040Y3984D03*
X1013630D03*
X1075197Y92126D03*
G54D51*
X526215Y184000D03*
X565585D03*
G54D46*
X92990Y252362D03*
X116790D03*
X1301120Y173278D03*
Y183908D03*
G54D50*
X487405Y255240D03*
G54D52*
X911616Y13778D03*
G54D41*
X16200Y120100D03*
X27200Y821800D03*
X1384200Y122800D03*
X1373200Y823500D03*
G54D42*
X26977Y151614D03*
X96189D03*
G54D48*
X336417Y21260D03*
G54D44*
X42587Y151614D03*
X80579D03*
G54D43*
X39370Y801181D03*
X1360630Y135826D03*
Y801181D03*
G54D47*
X293110Y55906D03*
G54D55*
X1333661Y55905D03*
X1376968Y21259D03*
Y90551D03*
G54D49*
X336417D03*
G54D40*
X75800Y229289D03*
G54D39*
X90459Y223184D03*
X64600Y342700D03*
G54D45*
X54378Y237402D03*
%LPC*%
G75*
G36*
G01X698648Y243750D02*
X645811D01*
X642250Y247311D01*
Y277689D01*
X643311Y278750D01*
X698689D01*
X700750Y276689D01*
Y245852D01*
X698648Y243750D01*
G37*
G36*
G01X795172Y177750D02*
Y180443D01*
G03X790415Y181007I-2412J0D01*
G02X789744Y180817I-389J93D01*
G01X749290Y221271D01*
Y221301D01*
X748851Y221740D01*
X748821D01*
X737811Y232750D01*
X706311D01*
X706098Y232963D01*
X706125Y233073D01*
G03X702973Y236225I-2525J627D01*
G01X702863Y236198D01*
X702250Y236811D01*
Y277689D01*
X703811Y279250D01*
X746811D01*
X767811Y300250D01*
X886689D01*
X907003Y279936D01*
X906954Y279814D01*
G03X909814Y276954I2046J-814D01*
G01X909936Y277003D01*
X922750Y264189D01*
Y218211D01*
X921789Y217250D01*
X901689D01*
X900601Y216162D01*
X900595Y216157D01*
G03X900374Y215935I1375J-1590D01*
G01X899750Y215311D01*
Y178711D01*
X898789Y177750D01*
X795172D01*
G37*
G36*
G01X887311Y301750D02*
X767189D01*
X746189Y280750D01*
X703189D01*
X701000Y278561D01*
X699311Y280250D01*
X679308D01*
X677250Y282308D01*
Y297304D01*
X677418Y297332D01*
G03Y302468I-418J2568D01*
G01X677250Y302496D01*
Y312189D01*
X704311Y339250D01*
X930689D01*
X970750Y299189D01*
Y262085D01*
X970748Y262072D01*
G03Y261548I2086J-262D01*
G01X970750Y261535D01*
Y258148D01*
X970748Y258135D01*
G03Y257611I2086J-262D01*
G01X970750Y257598D01*
Y254211D01*
X970748Y254198D01*
G03Y253674I2086J-262D01*
G01X970750Y253661D01*
Y250274D01*
X970748Y250261D01*
G03Y249737I2086J-262D01*
G01X970750Y249724D01*
Y246337D01*
X970748Y246324D01*
G03Y245800I2086J-262D01*
G01X970750Y245787D01*
Y242400D01*
X970748Y242387D01*
G03Y241863I2086J-262D01*
G01X970750Y241850D01*
Y238463D01*
X970748Y238450D01*
G03Y237926I2086J-262D01*
G01X970750Y237913D01*
Y234526D01*
X970748Y234513D01*
G03Y233989I2086J-262D01*
G01X970750Y233976D01*
Y230589D01*
X970748Y230576D01*
G03Y230052I2086J-262D01*
G01X970750Y230039D01*
Y226652D01*
X970748Y226639D01*
G03Y226115I2086J-262D01*
G01X970750Y226102D01*
Y222715D01*
X970748Y222702D01*
G03Y222178I2086J-262D01*
G01X970750Y222165D01*
Y218778D01*
X970748Y218765D01*
G03X970738Y218667I2086J-262D01*
G01X970733Y218594D01*
X969389Y217250D01*
X925511D01*
X924250Y218511D01*
Y264811D01*
X910997Y278064D01*
X911046Y278186D01*
G03X908186Y281046I-2046J814D01*
G01X908064Y280997D01*
X887311Y301750D01*
G37*
G36*
G01X772811Y157750D02*
X762842Y167719D01*
X762955Y167859D01*
G03X759859Y170955I-1713J1383D01*
G01X759719Y170842D01*
X740750Y189811D01*
Y215689D01*
X745301Y220240D01*
X748199D01*
X790348Y178090D01*
Y176043D01*
G03X795172I2412J0D01*
G01Y176250D01*
X899411D01*
X901250Y178089D01*
Y214689D01*
X902311Y215750D01*
X917789D01*
X918750Y214789D01*
Y214011D01*
X918089Y213350D01*
X916689D01*
X914750Y211411D01*
Y159311D01*
X913189Y157750D01*
X772811D01*
G37*
G36*
G01X947683Y101756D02*
G03X948242Y101193I1816J1245D01*
G01X948256Y101183D01*
X989850Y59589D01*
Y51758D01*
G03Y47638I778J-2060D01*
G01Y39411D01*
X987089Y36650D01*
X926189D01*
X923389Y33850D01*
X921537D01*
X921492Y33988D01*
G03X917308I-2092J-688D01*
G01X917263Y33850D01*
X873611D01*
X861411Y46050D01*
X857611D01*
X845350Y58311D01*
Y79789D01*
X846711Y81150D01*
X900700Y81127D01*
X904572Y84999D01*
Y128837D01*
X902569Y130840D01*
X893301D01*
X892824Y131317D01*
Y155753D01*
X893321Y156250D01*
X941589D01*
X942250Y155589D01*
Y107189D01*
X947683Y101756D01*
G37*
G36*
G01X951575Y103750D02*
X951522Y103871D01*
G03X947793Y104391I-2022J-871D01*
G02X947200Y104361I-310J253D01*
G01X943750Y107811D01*
Y156211D01*
X942211Y157750D01*
X918311D01*
X916250Y159811D01*
Y210789D01*
X917311Y211850D01*
X918711D01*
X920250Y213389D01*
Y214589D01*
X921411Y215750D01*
X970011D01*
X972250Y217989D01*
Y287202D01*
X974298Y289250D01*
X1217189D01*
X1220250Y286189D01*
Y200311D01*
X1160456Y140516D01*
X1158107D01*
G03X1156710Y137058I0J-2011D01*
G02X1156712Y136773I-139J-143D01*
G01X1123689Y103750D01*
X951575D01*
G37*
G36*
G01X1278689Y217250D02*
X1223822D01*
X1221750Y219322D01*
Y266692D01*
X1223808Y268750D01*
X1280189D01*
X1281750Y267189D01*
Y220311D01*
X1278689Y217250D01*
G37*
%LPD*%
G75*
G36*
G01X802200Y198010D02*
G02Y193990I0J-2010D01*
G01X798999D01*
G02X799000Y198010I1J2010D01*
G01X802200D01*
G37*
G36*
G01X787586Y193393D02*
G02X787614Y198215I14J2411D01*
G01X792013Y198189D01*
G02X791986Y193367I-14J-2411D01*
G01X787586Y193393D01*
G37*
G36*
G01X776396Y183890D02*
G02X781218I2411J0D01*
G01Y179489D01*
G02X776396Y179490I-2411J1D01*
G01Y183890D01*
G37*
G36*
G01X1141901Y139861D02*
G02X1141900Y135841I-1J-2010D01*
G01X1138700D01*
G02Y139861I0J2010D01*
G01X1141901D01*
G37*
G36*
G01X1124012Y130124D02*
G02X1119990I-2011J0D01*
G01Y133325D01*
G02X1124012Y133324I2011J-1D01*
G01Y130124D01*
G37*
G54D55*
X789850Y236220D03*
Y283464D03*
G54D29*
X213900Y274372D03*
X1348785Y179358D03*
X1323195D03*
G54D14*
X27300Y229000D03*
X26600Y249217D03*
Y253582D03*
X24000Y308700D03*
X24639Y321239D03*
X25350Y389000D03*
X17500Y412374D03*
X20713Y410087D03*
X21300Y429500D03*
X20713Y418326D03*
X23720Y472640D03*
X29300Y539850D03*
X24800Y540900D03*
X26100Y671200D03*
X24000Y659000D03*
X29500Y676500D03*
X25200Y712650D03*
X17500Y706300D03*
X21300Y728400D03*
X21108Y732713D03*
X21250Y742650D03*
X27000Y754400D03*
X41250Y216728D03*
X53400Y211928D03*
X38050Y216728D03*
X56600Y211928D03*
X60872Y274328D03*
X63700Y260725D03*
X55800Y266293D03*
X63700Y263925D03*
X55800Y269493D03*
X44900Y261750D03*
X35300Y303100D03*
X47912Y294940D03*
X39000Y299500D03*
X53100Y279500D03*
X47800Y309400D03*
X31662Y303262D03*
X58700Y308600D03*
X61800Y306900D03*
X38800Y302900D03*
X62200Y288256D03*
X58383Y294947D03*
X47355Y303376D03*
X47991Y299958D03*
X49934Y280811D03*
X38500Y321400D03*
X58100Y334600D03*
X62400Y334500D03*
X31700Y314700D03*
X52050Y316100D03*
X51050Y321650D03*
X62400Y342700D03*
X38518Y376916D03*
X34153D03*
X39866Y371366D03*
X52521Y350357D03*
X54200Y347400D03*
X63500Y353960D03*
X62838Y392392D03*
X39300Y389557D03*
X35709Y426942D03*
X43500Y418802D03*
X47734Y465792D03*
X45531Y474400D03*
X64820Y455887D03*
X64680Y452389D03*
X64500Y459400D03*
X36750Y462900D03*
X53200Y462500D03*
X49812Y479921D03*
X33900Y469300D03*
X46500Y460300D03*
X46087Y455819D03*
X50140Y494559D03*
X60987Y489223D03*
X63519Y505320D03*
X62298Y484200D03*
X35700Y488500D03*
X60150Y506450D03*
X50140Y490750D03*
X60900Y495122D03*
X61870Y515670D03*
X60300Y533900D03*
X61128Y519646D03*
X61800Y537000D03*
X55950Y564500D03*
Y572500D03*
X63000Y558930D03*
X62611Y608289D03*
X62400Y624500D03*
X53000Y645000D03*
X63300Y634800D03*
X43600Y665700D03*
X54200Y666800D03*
X60700Y682100D03*
X47800Y666400D03*
X35766Y673178D03*
X34500Y666500D03*
X39900Y678100D03*
X33600Y675800D03*
X43100Y670900D03*
X36624Y669155D03*
X47300Y704400D03*
X42300Y704900D03*
X62000Y713000D03*
X45800Y685100D03*
X42100Y684000D03*
X63300Y697200D03*
X59100Y705600D03*
X42130Y694440D03*
X38000Y684000D03*
X59300Y734900D03*
X54300Y729900D03*
X49300Y734900D03*
X54300Y739900D03*
Y734900D03*
X56590Y720410D03*
X47800Y772900D03*
X35000Y769900D03*
X39000D03*
X42800Y770000D03*
X52500Y779600D03*
X64900Y780500D03*
X88259Y223184D03*
X92659D03*
X78000Y229289D03*
X73600D03*
X77400Y216528D03*
X88800Y210851D03*
X74200Y216528D03*
X92000Y210851D03*
X97480Y266420D03*
X77527Y255800D03*
X94530Y264671D03*
X75800Y274100D03*
X68100Y255000D03*
X89400Y279300D03*
X96798Y301484D03*
Y297915D03*
X95700Y293900D03*
X73125Y288231D03*
X76325D03*
X65400Y288256D03*
X84600Y303000D03*
X66800Y342700D03*
X83500Y344200D03*
X80300D03*
X77421Y322470D03*
X74221D03*
X79455Y357174D03*
X76055Y357145D03*
X82500Y362890D03*
X79267Y410185D03*
X80940Y395989D03*
X86904Y385798D03*
X72708Y382055D03*
X68365Y381464D03*
X84700Y396000D03*
X96351Y443000D03*
Y438600D03*
X85042Y439144D03*
X91200Y448800D03*
Y453200D03*
X89500Y466600D03*
X85748Y475813D03*
X73232Y476912D03*
X97100Y466500D03*
X98400Y454400D03*
X76100Y483400D03*
X77700Y502500D03*
X88573Y503935D03*
X70910Y502219D03*
X67700Y499120D03*
X77700Y522500D03*
X88204Y543283D03*
X89200Y518700D03*
Y528500D03*
X65600Y543200D03*
X75600Y518600D03*
X67700Y518500D03*
X67162Y515142D03*
X77300Y531238D03*
X77700Y538500D03*
X74301Y538390D03*
X65800Y538900D03*
X74300Y533600D03*
X73900Y527050D03*
X77372Y526885D03*
X73700Y542600D03*
X70000Y542500D03*
X74000Y557000D03*
X77500Y554500D03*
X87337Y569268D03*
X84226Y577924D03*
X87200Y565785D03*
X77400Y550400D03*
X65381Y548719D03*
X87608Y557685D03*
X69100Y549200D03*
X73700Y549300D03*
X92000Y591200D03*
X69500Y586000D03*
X66000Y604800D03*
X88000Y613600D03*
X81000Y589000D03*
X78300Y637750D03*
X94950Y677850D03*
X74500Y713400D03*
X91450Y707650D03*
X65350Y690356D03*
X89400Y749200D03*
X89300Y736300D03*
X95400Y731600D03*
Y728200D03*
X68900Y730000D03*
X68465Y736229D03*
X85800Y727500D03*
Y731000D03*
X74300Y769950D03*
X89800Y753400D03*
X69800Y772700D03*
X86900Y757900D03*
X89400Y762400D03*
X93100Y813200D03*
X93300Y818900D03*
X108631Y168836D03*
X111967Y199632D03*
X119800Y234531D03*
X103100Y211600D03*
X109600Y276850D03*
X112732Y272786D03*
X107340Y266140D03*
X101463Y268811D03*
X102499Y281183D03*
X108500Y284000D03*
X107213Y301192D03*
X120700Y282400D03*
X100500Y285300D03*
X113915Y307600D03*
X117484D03*
X101630Y312236D03*
X106717Y335600D03*
X117700Y323400D03*
X111900Y344200D03*
X113000Y336000D03*
X107558Y321012D03*
X122000Y343300D03*
X100277Y336077D03*
X102000Y364700D03*
X122645Y367966D03*
X117300Y361700D03*
X115951Y384138D03*
X111950Y392050D03*
X104204Y383661D03*
X129500Y412400D03*
X124290Y401910D03*
X125718Y383302D03*
X125600Y386700D03*
X107358Y409942D03*
X126122Y432323D03*
X116235Y444665D03*
X103179Y423267D03*
X103176Y434180D03*
X110406Y417067D03*
X113518Y420179D03*
X131304Y418855D03*
X131004Y422710D03*
X130633Y444763D03*
X120200Y436400D03*
X120000Y451285D03*
X107900Y448900D03*
X101200Y470400D03*
X129520Y448660D03*
X127820Y452280D03*
X123696Y454452D03*
X114400Y550000D03*
X102870Y565740D03*
Y561340D03*
X105851Y611436D03*
X102000Y602500D03*
X101750Y595600D03*
X128220Y620392D03*
X125581Y641436D03*
X109051Y645936D03*
X124150Y707050D03*
X106900Y738600D03*
Y721300D03*
X115000Y717600D03*
X107000Y717800D03*
X111300Y756000D03*
X109900Y828800D03*
X105400Y828700D03*
X103200Y825400D03*
X115500Y825500D03*
X107600D03*
X120000Y843500D03*
X126500Y878200D03*
Y871000D03*
X129000Y875000D03*
X117500Y878200D03*
X122000D03*
X124500Y875000D03*
X120000Y865000D03*
Y875000D03*
Y853500D03*
X162500Y173500D03*
X155026Y212580D03*
X155662Y266438D03*
X159662Y266600D03*
X162910Y244290D03*
X166087Y304350D03*
X134800Y329600D03*
X144595Y312861D03*
X137862Y361723D03*
X161311Y371428D03*
X141216Y361163D03*
X145027D03*
X156573Y371799D03*
X146105Y403610D03*
X155657Y384291D03*
X137000Y436700D03*
X145901Y441262D03*
X153100Y439000D03*
X136500Y417400D03*
X152978Y435602D03*
X137344Y446737D03*
X137000Y451300D03*
X163440Y453020D03*
X143547Y477976D03*
X137000Y454700D03*
X159239Y449079D03*
X159082Y452509D03*
X153019Y622720D03*
X159716Y620392D03*
X166015D03*
X136651Y653036D03*
X162100Y677800D03*
X164400Y668300D03*
X160500Y689500D03*
X150000Y701500D03*
X142500Y709000D03*
X137000Y715500D03*
X164500Y693500D03*
X144400Y731600D03*
Y728200D03*
X150450Y744150D03*
X146450Y736150D03*
X135700Y745200D03*
X163800Y771000D03*
X160400D03*
X160700Y753400D03*
X139250Y791250D03*
X143250Y799250D03*
X153500Y808500D03*
X163800Y820000D03*
X160400D03*
X191800Y189600D03*
X196018Y204200D03*
X183400Y221600D03*
X171100Y247500D03*
X167600Y247600D03*
X193303Y264310D03*
X167700Y296882D03*
Y292517D03*
X170062Y304556D03*
X174943Y321015D03*
X167687Y329434D03*
X192407Y320262D03*
X180571Y327023D03*
X176674Y344934D03*
X189365Y329905D03*
X179381Y369903D03*
X196529Y352284D03*
X185970Y358962D03*
X195940Y348814D03*
X182969Y352641D03*
X192150Y406429D03*
X197000Y404000D03*
X171434Y398093D03*
X177550Y407850D03*
X166321Y388316D03*
X197850Y437450D03*
X185000Y419900D03*
X197531Y451187D03*
X189381Y451394D03*
X193718D03*
X196239Y462262D03*
X175912Y450747D03*
X166534Y450821D03*
X186675Y453505D03*
X177500Y454300D03*
X199900Y544500D03*
X196782Y563564D03*
X197334Y567232D03*
X189500Y567700D03*
X185500Y577300D03*
X184189Y564504D03*
X185500Y567700D03*
X193001Y574708D03*
X181000Y585000D03*
Y581500D03*
Y595200D03*
X168769Y622720D03*
X171300Y678300D03*
X175200Y678500D03*
X199900Y692000D03*
X171000Y715900D03*
X167600D03*
X178750Y712250D03*
X189000Y684500D03*
X185000D03*
X167000Y686500D03*
X199900Y747500D03*
Y741000D03*
X184700Y729400D03*
X182750Y720250D03*
X193000Y729500D03*
X171000Y764900D03*
X167600D03*
X182750Y775750D03*
X178000Y753400D03*
X178750Y767750D03*
X199900Y796500D03*
X177500Y784500D03*
X170800Y808500D03*
X193000Y785000D03*
X197420Y821701D03*
X194120Y830301D03*
X190920D03*
X176900Y867600D03*
X173500D03*
X197218Y871676D03*
X228163Y68589D03*
X222354Y103006D03*
X228163Y78589D03*
X227606Y98642D03*
X223641Y99302D03*
X228163Y93589D03*
Y88589D03*
X228007Y123787D03*
X233500Y137000D03*
X220300Y129300D03*
X222356Y133438D03*
X228708Y127115D03*
X215136Y142786D03*
X218299Y123319D03*
X224576Y116678D03*
X221418Y109634D03*
X210478Y151203D03*
X233537Y160630D03*
X210484Y179525D03*
X206297Y188492D03*
X209866D03*
X214794Y212100D03*
X206200Y247500D03*
X209200Y252800D03*
X230400Y283400D03*
X222200Y300500D03*
X205840Y325381D03*
X210177D03*
X221460Y335475D03*
Y339875D03*
X228100Y364600D03*
X219018Y378000D03*
X223383D03*
X217000Y360000D03*
X219580Y356970D03*
X214776Y352807D03*
X212536Y349805D03*
X205750Y408250D03*
X205915Y422424D03*
X217190Y428485D03*
X212200Y428800D03*
X212000Y438713D03*
X217500Y441992D03*
X205200Y442900D03*
X220897Y441833D03*
X220800Y446000D03*
X200100Y415100D03*
X201868Y451187D03*
X227700Y476537D03*
Y472200D03*
X216404Y469751D03*
X216282Y463288D03*
X230572Y455128D03*
X228900Y446800D03*
X219300Y508700D03*
X228298Y488100D03*
X228347Y484700D03*
X219700Y489800D03*
X202700Y495400D03*
X206700Y498000D03*
X200917Y490578D03*
X203550Y484522D03*
X233290Y493277D03*
X206700Y494000D03*
X203500Y499200D03*
X207026Y483956D03*
X219800Y493700D03*
X218906Y483186D03*
X226300Y505700D03*
X226530Y502307D03*
X216873Y516458D03*
X203300Y538500D03*
X206700Y544500D03*
Y538500D03*
X225000Y541300D03*
X229200Y514800D03*
X216300Y546350D03*
X203300Y544500D03*
Y548500D03*
X219700Y550500D03*
X218780Y560082D03*
X206700Y548500D03*
X202300Y559763D03*
X222300Y577300D03*
X216563Y555908D03*
X229800Y558500D03*
X206700Y554500D03*
X203304Y554684D03*
X205700Y559763D03*
X222500Y573220D03*
X216241Y563095D03*
X227500Y603500D03*
X201000Y674000D03*
X206952Y655370D03*
X203300Y692000D03*
X219000Y694000D03*
X231500Y699000D03*
X217000Y705500D03*
X203300Y747500D03*
Y741000D03*
X210300Y729500D03*
X217000Y761000D03*
X228550Y772700D03*
X231750D03*
X203300Y796500D03*
X210300Y785000D03*
X200620Y821701D03*
X231915Y830301D03*
X219317D03*
X206718D03*
X228715D03*
X216117D03*
X203518D03*
X225615Y875176D03*
X213017D03*
X200418Y871676D03*
X222415Y875176D03*
X209817D03*
X257759Y68589D03*
X264817Y105350D03*
X257731Y78589D03*
X258100Y93589D03*
X257912Y101408D03*
X258029Y97353D03*
X260562Y85988D03*
X254000Y131500D03*
X246500Y139000D03*
X243000D03*
X258068Y110180D03*
X259331Y118580D03*
X264443Y109587D03*
X257422Y121792D03*
X243618Y143381D03*
X243500Y147500D03*
X244300Y226700D03*
X266500Y239400D03*
X245400Y296500D03*
X248160Y343140D03*
X267300Y362200D03*
X244000Y377617D03*
Y381982D03*
X258500Y391200D03*
X239100Y399200D03*
X251700Y421600D03*
Y425200D03*
X238400Y416200D03*
X235750Y419500D03*
X262900Y438700D03*
X246375Y440725D03*
X265100Y443300D03*
X264100Y425400D03*
X249342Y439064D03*
X251800Y470100D03*
X248500Y465000D03*
X263700Y474600D03*
X257493Y456679D03*
X253302D03*
X257400Y477300D03*
X235850Y455050D03*
X246300Y478600D03*
Y485400D03*
X246407Y488799D03*
X256300Y494500D03*
X244100Y499900D03*
X246800Y496800D03*
X257400Y481637D03*
X256300Y486000D03*
Y490000D03*
X242800Y495486D03*
X246500Y493400D03*
X240450Y499400D03*
X236737Y493170D03*
X243200Y508000D03*
X250200Y506600D03*
X264522Y511690D03*
X260407Y502674D03*
X257207D03*
X246300Y482000D03*
X239139Y525077D03*
X239321Y521081D03*
X264500Y521309D03*
X261100Y521250D03*
X250100Y537100D03*
X236100Y517100D03*
X263300Y526300D03*
X234777Y550569D03*
X255738Y574238D03*
X253500Y590500D03*
X257413D03*
X236000Y656000D03*
X256600Y652200D03*
X241000Y712500D03*
X262628Y744470D03*
X266980Y723854D03*
X241000Y721500D03*
X258100Y726100D03*
X241000Y725500D03*
Y718000D03*
X263181Y772181D03*
X266561Y830301D03*
X253962D03*
X263361D03*
X250762D03*
X260261Y875176D03*
X238213D03*
X257061D03*
X235013D03*
X290000Y141100D03*
X274250Y133750D03*
X292000Y130000D03*
X285500D03*
X284440Y139580D03*
X285250Y133750D03*
X294500Y152500D03*
X286000Y143800D03*
X286100Y153900D03*
X280000D03*
X290500Y152500D03*
X275000Y147500D03*
X277800Y208500D03*
X271231Y237031D03*
X283622Y226340D03*
X279257D03*
X277300Y304800D03*
X297090Y311350D03*
X282700Y300100D03*
X299600Y297662D03*
X287200Y326802D03*
X287800Y311600D03*
X267979Y342500D03*
X295400Y325390D03*
X283700Y322100D03*
X288270Y365240D03*
X297729Y351029D03*
X294009Y363063D03*
X293800Y436100D03*
X301170Y462780D03*
X301162Y459290D03*
X273783Y476100D03*
X283400Y477900D03*
X275900Y467300D03*
X285800Y460810D03*
X290838Y501600D03*
X286169Y502000D03*
X285776Y489300D03*
X272860Y489147D03*
X282400Y487300D03*
X295876Y520800D03*
X296200Y566900D03*
X290000Y578165D03*
X279994Y554794D03*
X283600Y551400D03*
X291000Y561450D03*
X280200Y551400D03*
X289835Y583165D03*
Y588165D03*
X269000Y589000D03*
X269335Y593165D03*
X297750Y592750D03*
X281800Y638900D03*
X288400Y626100D03*
Y634200D03*
X292500Y630200D03*
X271500Y639500D03*
X298406Y706000D03*
X290338Y715800D03*
X275609Y726886D03*
X270556Y716702D03*
X269500Y736150D03*
X286500Y740500D03*
X287278Y729031D03*
X286406Y716531D03*
X296132Y726171D03*
X290720Y726333D03*
X285333Y726241D03*
X282406Y716598D03*
X298620Y728596D03*
X283500Y765631D03*
X268193Y755633D03*
X293692Y765571D03*
X287115Y765584D03*
X281500Y752000D03*
X299184Y765691D03*
X279159Y830301D03*
X275959D03*
X285500Y866200D03*
X272859Y875176D03*
X282300Y866200D03*
X269659Y875176D03*
X306900Y251000D03*
X302500Y251600D03*
X311882Y310550D03*
X306800Y290500D03*
X307425Y309838D03*
X303517Y309777D03*
X312900Y290450D03*
X321300Y301500D03*
X334200Y299600D03*
X313200Y299900D03*
X331800Y309100D03*
X310485Y314670D03*
X328800Y315900D03*
X326041Y325000D03*
X310839Y344339D03*
X315300Y344500D03*
X315900Y320900D03*
X313100Y371038D03*
Y374438D03*
X301320Y362500D03*
X301929Y351100D03*
X313500Y437400D03*
Y441000D03*
X313300Y429603D03*
X313294Y434006D03*
X302140Y444160D03*
X306521Y463576D03*
X304293Y466146D03*
X329014Y472022D03*
X322268Y466591D03*
X322305Y469991D03*
X321900Y459800D03*
X322036Y463198D03*
X327512Y509612D03*
X303800Y505100D03*
X304400Y511400D03*
X327589Y504300D03*
X333102Y485902D03*
X330000Y501900D03*
X305500Y483550D03*
X320500Y531000D03*
X321000Y527000D03*
X306900Y529100D03*
X311500Y548000D03*
X314900D03*
X309000Y679000D03*
X305500Y676400D03*
X334800Y712000D03*
X302406Y706031D03*
X306406D03*
X317300Y739300D03*
X302000Y740800D03*
X320000Y718200D03*
X323600Y717800D03*
X301310Y726403D03*
X326000Y729000D03*
X315132Y727197D03*
X307278Y726198D03*
X311200Y765500D03*
X311406Y775198D03*
X302700Y765400D03*
X315406Y765598D03*
Y775200D03*
X307406Y775198D03*
X329553Y830301D03*
X316954D03*
X326353D03*
X313754D03*
X323253Y875176D03*
X310955Y865676D03*
X332651Y875176D03*
X320053D03*
X307755Y865676D03*
X362528Y123931D03*
X358917Y124122D03*
X355069D03*
X352600Y128200D03*
Y132537D03*
X337000Y162000D03*
X354800Y171400D03*
X358300D03*
X354800Y166900D03*
X358300D03*
X354800Y162400D03*
X358300D03*
X362300D03*
Y166900D03*
Y171400D03*
X354800Y181900D03*
X358300D03*
X354800Y176900D03*
X358300D03*
X362300D03*
Y181900D03*
X345820Y256570D03*
X349970Y256720D03*
X341652Y305034D03*
Y301534D03*
X362500Y341700D03*
X362825Y336000D03*
X359132Y326647D03*
X351515Y327915D03*
X356953Y353653D03*
X359403Y351203D03*
X352003Y358603D03*
X354505Y356102D03*
X360820Y359299D03*
X363270Y356940D03*
X355872Y363965D03*
X358362Y361649D03*
X335570Y491460D03*
X367000Y704000D03*
X360000D03*
X344200Y696300D03*
X354300Y696000D03*
Y704500D03*
X363500Y704000D03*
X364354Y731801D03*
X362091Y729538D03*
X367675Y723000D03*
X367348Y830301D03*
X354750D03*
X342151D03*
X364148D03*
X351550D03*
X338951D03*
X361048Y875176D03*
X348450D03*
X335851D03*
X357848D03*
X345250D03*
X401300Y156715D03*
Y153215D03*
X400400Y189100D03*
X383600Y203200D03*
X376600Y261350D03*
X381700Y265800D03*
X368900Y315700D03*
X370700Y353900D03*
X370500Y705500D03*
X370875Y723000D03*
X401994Y830301D03*
X389396D03*
X398794D03*
X386196D03*
X395694Y875176D03*
X383096D03*
X392494D03*
X379896D03*
X403600Y142542D03*
X433000Y169700D03*
X435161Y166892D03*
X403600Y146042D03*
X422876Y199830D03*
Y204195D03*
X421757Y177999D03*
X411400Y183900D03*
X433400Y176800D03*
X410900Y217100D03*
X404040Y318900D03*
Y323300D03*
X427191Y830301D03*
X414593D03*
X423991D03*
X411393D03*
X420891Y875176D03*
X408292D03*
X417691D03*
X405092D03*
X466000Y62300D03*
X457700D03*
X465127Y57727D03*
X454926Y118791D03*
X455800Y110200D03*
X438561Y166892D03*
X456500Y169783D03*
Y165418D03*
X464086Y287614D03*
Y340500D03*
X455450Y376050D03*
X469700Y393300D03*
X459450Y384050D03*
X469000Y784000D03*
X461300Y813100D03*
X457900D03*
X474400Y62300D03*
X483250Y59480D03*
X496782Y134315D03*
X474990Y122660D03*
X480910Y164099D03*
X480800Y160700D03*
X498900Y171800D03*
X498000Y194200D03*
X477037Y333841D03*
X473637Y333876D03*
X500198Y324041D03*
X480532Y321332D03*
X480000Y355800D03*
X476600D03*
X493700Y369300D03*
X487000Y393300D03*
X480368Y405606D03*
X476531D03*
X482925Y777422D03*
X489522Y780127D03*
X478000Y777500D03*
X483850Y773800D03*
X500778Y781031D03*
X499906Y768531D03*
X497910Y778824D03*
X495906Y768598D03*
X480100Y784575D03*
X497000Y817500D03*
X483000Y788150D03*
X499000Y793000D03*
X485300Y811750D03*
X500415Y817532D03*
X494582Y804000D03*
X477206Y820648D03*
X500700Y828100D03*
X500807Y831499D03*
X491906Y827403D03*
X487906D03*
X509369Y141559D03*
X530800Y123900D03*
X507861Y134154D03*
X519300Y138871D03*
X530177Y140708D03*
X516100Y138871D03*
X526977Y140708D03*
X529176Y151713D03*
X532560Y152046D03*
X534000Y167400D03*
X535960Y151999D03*
X507300Y175500D03*
X503975Y172372D03*
X518686Y163800D03*
Y168200D03*
X517599Y229658D03*
X531232Y229927D03*
X510462Y261315D03*
X525881Y287776D03*
X509143Y284391D03*
X529881Y287376D03*
X529126Y342336D03*
X532978Y371023D03*
X534500Y395100D03*
X528850Y394750D03*
X515900Y768300D03*
X531500Y774500D03*
X531600Y770200D03*
X515278Y779198D03*
X519748Y768297D03*
X507729Y778198D03*
X504278Y779198D03*
X507906Y768531D03*
X528179Y782555D03*
X524795Y778529D03*
X511484Y778515D03*
X515650Y764500D03*
X503906Y768598D03*
X519906Y764900D03*
X532000Y792500D03*
X515000D03*
X524700Y817500D03*
X507044Y817569D03*
X516943Y817401D03*
X528906Y817598D03*
X512716Y817550D03*
X508579Y827421D03*
X527500Y836200D03*
X512679Y827500D03*
X562603Y140881D03*
X544800Y137769D03*
X541600D03*
X549100Y126900D03*
X566531Y143123D03*
X570754Y147365D03*
X546800Y163450D03*
X564483Y167935D03*
X558121Y167249D03*
X548700Y152200D03*
X545500D03*
X547173Y167987D03*
X561567Y205767D03*
X569500Y240225D03*
X546494Y216010D03*
X539798Y228856D03*
X539934Y232660D03*
X540035Y236294D03*
X541637Y263240D03*
X545974D03*
X541681Y297976D03*
X539481Y286676D03*
X544993Y281352D03*
X539400Y376444D03*
X561300Y369500D03*
X552720Y364180D03*
X539400Y380781D03*
X559973Y387638D03*
X561912Y390762D03*
X567150Y415750D03*
X560900Y413700D03*
X544000Y761000D03*
X540500Y781000D03*
X547395Y761198D03*
X540500Y761000D03*
X561050Y830301D03*
X548451D03*
X570448D03*
X557850D03*
X545251D03*
X567348Y875176D03*
X554750D03*
X542151D03*
X564148D03*
X551550D03*
X538951D03*
X577650Y137780D03*
X587850Y137800D03*
X604450Y137780D03*
X574450D03*
X584650Y137800D03*
X601250Y137780D03*
X597350Y149950D03*
X594150D03*
X596253Y210000D03*
X603000Y190710D03*
X579811Y179500D03*
X582400Y209500D03*
X597813Y220858D03*
X587438Y230850D03*
X576100Y234500D03*
X592563Y228308D03*
X588963Y227408D03*
X587400Y238200D03*
X600800Y337400D03*
X597600Y339100D03*
X604400Y421200D03*
X579900Y427400D03*
X598845Y830301D03*
X586246D03*
X573648D03*
X595645D03*
X583046D03*
X592545Y875176D03*
X579947D03*
X601944D03*
X589345D03*
X576747D03*
X614721Y138287D03*
X608089Y131519D03*
X627826Y137880D03*
X638150D03*
X624626D03*
X634950D03*
X617000Y144500D03*
X636950Y149650D03*
X635482Y207733D03*
X607700Y211800D03*
X608800Y221400D03*
X635863Y216308D03*
X635190Y219641D03*
X631063Y242108D03*
X616970Y235017D03*
X629663Y221708D03*
X616718Y238408D03*
X627363Y224358D03*
X637300Y234500D03*
X628563Y249108D03*
X624101Y330010D03*
X627500Y329900D03*
X622629Y344635D03*
X616640Y342230D03*
X620000Y341500D03*
X618600Y357100D03*
X609000Y390350D03*
X615500Y420100D03*
X619100Y418000D03*
X636640Y830301D03*
X624042D03*
X611443D03*
X633440D03*
X620842D03*
X608243D03*
X630340Y875176D03*
X617742D03*
X605144D03*
X627140D03*
X614542D03*
X654500Y143000D03*
X647000D03*
X640150Y149650D03*
X640400Y218200D03*
X649400Y234500D03*
X642463Y241608D03*
X638963D03*
X660700Y212000D03*
X643000Y343000D03*
X643750Y321500D03*
X640550D03*
X643000Y369500D03*
X648792Y358431D03*
X660244Y352200D03*
Y349000D03*
X645800Y780500D03*
Y776900D03*
Y783900D03*
X671285Y830301D03*
X658687D03*
X668085D03*
X655487D03*
X664986Y875176D03*
X652388D03*
X661786D03*
X649188D03*
X687900Y208100D03*
X697494Y186256D03*
Y181919D03*
X693300Y181200D03*
X674500Y212000D03*
X680100Y378718D03*
X683600D03*
X696482Y830301D03*
X683884D03*
X693282D03*
X680684D03*
X702400Y868800D03*
X690183Y875176D03*
X677585D03*
X699200Y868800D03*
X686983Y875176D03*
X674385D03*
X728395Y-7315D03*
X713461Y-3006D03*
X729132Y3575D03*
X724018Y5719D03*
X729000Y24800D03*
X725314Y24751D03*
X721890Y24887D03*
X719008Y21999D03*
X707051Y12174D03*
X738384Y8232D03*
X722955Y33095D03*
X726155D03*
X723200Y42300D03*
X726609Y49251D03*
Y46051D03*
X732900Y44900D03*
X730021Y42235D03*
X732500Y98421D03*
X720800Y102150D03*
Y93150D03*
Y78150D03*
X732500Y101621D03*
X720800Y105350D03*
Y96350D03*
Y81350D03*
Y114150D03*
Y117350D03*
X712495Y816195D03*
X727978Y830301D03*
X737377D03*
X724778D03*
X714900Y818600D03*
X734277Y875176D03*
X731077D03*
X746329Y-7789D03*
X771715Y6840D03*
X741600Y41000D03*
X742290Y68550D03*
X750130Y63340D03*
X748300Y53800D03*
X772000Y64200D03*
X755700Y79100D03*
X749800Y91400D03*
X753700Y102900D03*
X759600Y79200D03*
X743490Y111940D03*
X765000Y112800D03*
X768777Y171450D03*
X761242Y169242D03*
X765579D03*
X771400Y185919D03*
X766244Y185897D03*
X748237Y194042D03*
X751737D03*
X766950Y189252D03*
X763562Y189539D03*
X770385Y189165D03*
X765774Y830301D03*
X753175D03*
X740577D03*
X762574D03*
X749975D03*
X772073Y875176D03*
X759474D03*
X746876D03*
X768873D03*
X756274D03*
X743676D03*
X790150Y-1400D03*
X788408Y-4321D03*
X798061Y-6439D03*
X806152Y51692D03*
X791300Y74200D03*
X775381Y66115D03*
X778800Y66388D03*
X782551Y67144D03*
X786333Y66963D03*
X791200Y125300D03*
X796051Y175147D03*
X806665Y174050D03*
X803265D03*
X792760Y176043D03*
X799000Y196000D03*
X802200D03*
X796089Y181182D03*
X775397Y179165D03*
Y184215D03*
X792390Y199166D03*
X786463Y199019D03*
X803169Y198850D03*
X797890Y198918D03*
X792000Y195778D03*
X787600Y195804D03*
X773984Y189118D03*
X792760Y180443D03*
X778807Y183890D03*
Y179490D03*
X803569Y830301D03*
X790970D03*
X778372D03*
X800369D03*
X787770D03*
X775172D03*
X797270Y875176D03*
X784671D03*
X806668D03*
X794070D03*
X781471D03*
X807514Y2199D03*
X813900Y12900D03*
X838252Y20800D03*
X834500D03*
X830500D03*
X828283Y24734D03*
X824462Y25770D03*
X821877Y21090D03*
X823996Y44276D03*
X820004Y44234D03*
X828700Y48800D03*
X808114Y67634D03*
X816043Y94981D03*
Y99318D03*
X823551Y80551D03*
X819000Y97100D03*
X809000Y76000D03*
X810000Y109400D03*
X840500Y735500D03*
X837000D03*
X839990Y789230D03*
X816167Y830301D03*
X838164D03*
X812967D03*
X835065Y875176D03*
X809868D03*
X831865D03*
X861000Y350D03*
X857453Y303D03*
X863300Y23575D03*
X851100Y9100D03*
X849051Y20908D03*
X845052Y20800D03*
X841652D03*
X858500Y28000D03*
X858100Y21400D03*
X858500Y36000D03*
X847000Y9100D03*
X870600Y18915D03*
X854252Y20800D03*
X859200Y47100D03*
X848623Y70757D03*
X852019Y70589D03*
X855421Y70551D03*
X858821Y70614D03*
X859000Y43500D03*
X871550Y56450D03*
X858800Y52200D03*
X868800Y49200D03*
Y85300D03*
X871696Y87082D03*
X868200Y116000D03*
X846702Y117371D03*
X854400Y117500D03*
X861300Y117800D03*
X864800Y707700D03*
X868200D03*
X852895Y748648D03*
X869406Y745531D03*
X848000Y735500D03*
X865406Y745598D03*
X873367Y745335D03*
X844000Y735500D03*
X854049Y757573D03*
X857406Y755198D03*
X861406D03*
X858126Y763600D03*
X841500Y771000D03*
X874000Y772000D03*
X869562Y758457D03*
X844500Y758000D03*
X867410Y755824D03*
X866878Y794531D03*
X853500Y798000D03*
X846706Y797648D03*
X870278Y794531D03*
X874570Y811820D03*
X861406Y804403D03*
X857406D03*
X853962Y830301D03*
X841364D03*
X850762D03*
X847663Y875176D03*
X844463D03*
X883800Y-500D03*
X881700Y2300D03*
X899769Y4355D03*
X887800Y40100D03*
X896500Y9500D03*
X877500Y23600D03*
X900250Y38150D03*
X888474Y9173D03*
X900200Y9600D03*
X883800Y41400D03*
X907750Y51750D03*
X894110Y49250D03*
X878800Y49600D03*
X875050Y56250D03*
X895080Y52828D03*
X900501Y48705D03*
X883700Y50700D03*
X905488Y54479D03*
X878394Y85780D03*
X875001Y86003D03*
X901899Y85942D03*
X892900Y85300D03*
X885042Y85292D03*
X888600Y85700D03*
X897600Y85500D03*
X908500Y270500D03*
Y275000D03*
Y267000D03*
X907500Y325000D03*
X895800Y738400D03*
X893400Y745100D03*
X884700Y721100D03*
X896500Y734000D03*
X877000Y745000D03*
X892100Y721100D03*
X881200Y721300D03*
X888400Y721400D03*
X889900Y769600D03*
X884778Y756198D03*
X876036Y755481D03*
X894465Y755501D03*
X891056Y755641D03*
X882227Y758835D03*
X894200Y794500D03*
X877930Y796880D03*
X876470Y808710D03*
X906396Y810300D03*
X886288Y794372D03*
X898700Y794200D03*
Y816000D03*
X882290Y796770D03*
X881720Y807390D03*
X906450Y806900D03*
X906092Y813687D03*
X894406Y818000D03*
X888100Y823338D03*
X890200Y819200D03*
X912000Y41000D03*
X911800Y37000D03*
X938000Y30300D03*
X919400Y33300D03*
X915486Y41030D03*
X918952Y40680D03*
X912000Y45000D03*
X939064Y58104D03*
X934881Y57322D03*
X909797Y55037D03*
X910000Y85300D03*
X937642Y85562D03*
X926093Y85239D03*
X929213Y86593D03*
X934438Y86700D03*
X919050Y85500D03*
X913979Y86580D03*
X935000Y97400D03*
X927100Y96900D03*
X929800Y105900D03*
X909000Y279000D03*
X909500Y283000D03*
Y338000D03*
X974100Y19600D03*
X970064Y18764D03*
X963700Y21700D03*
X959877Y26978D03*
X952500Y75100D03*
X949102Y74964D03*
X947900Y67900D03*
X959300Y68600D03*
Y72000D03*
X964105Y62308D03*
X959855Y61107D03*
X956687Y85482D03*
X942800Y85700D03*
X948200Y85900D03*
X953301Y85793D03*
X956500Y108000D03*
X949500Y103000D03*
Y97500D03*
X949893Y106378D03*
X949828Y109778D03*
X960500Y607000D03*
X953500D03*
X956900D03*
X1008353Y-1940D03*
X985579Y26494D03*
X985403Y22993D03*
X994650Y39880D03*
X990628Y49698D03*
X997007Y49560D03*
X1008508Y47704D03*
X982500Y271500D03*
Y275500D03*
X982000Y267500D03*
X983500Y279500D03*
Y283500D03*
X1022711Y-4975D03*
X1012177Y-2940D03*
X1019859Y-7642D03*
X1033017Y14743D03*
X1033554Y30216D03*
X1040121Y26870D03*
X1039822Y35743D03*
X1017908Y41556D03*
X1018900Y14198D03*
X1010975Y29017D03*
X1029553Y13981D03*
X1030139Y30209D03*
X1024432Y43718D03*
X1011300Y53000D03*
X1024318Y51554D03*
X1014700Y53700D03*
X1040241Y61043D03*
X1033517Y48934D03*
X1036854Y47110D03*
X1019900Y108500D03*
X1015948D03*
X1034500D03*
X1027483Y108431D03*
X1024000Y108500D03*
X1037900D03*
X1041300D03*
X1030883Y108438D03*
X1041314Y830301D03*
X1038214Y875176D03*
X1035014D03*
X1062044Y-4173D03*
X1065620Y-4335D03*
X1072800Y-800D03*
X1045850Y6228D03*
X1069200Y-4200D03*
X1060800Y10100D03*
X1044050Y28815D03*
X1062088Y40597D03*
X1072804Y19894D03*
X1064900Y10400D03*
X1065700Y32888D03*
Y36088D03*
X1061200Y20888D03*
Y24088D03*
X1056200Y10100D03*
X1065657Y28946D03*
X1047500Y41500D03*
X1051000D03*
X1076970Y30411D03*
X1052600Y14400D03*
X1049772Y57259D03*
X1049470Y53749D03*
X1050875Y61090D03*
X1057000Y54500D03*
X1071135Y60375D03*
X1057000Y57700D03*
X1071135Y57175D03*
X1057000Y107700D03*
X1057259Y77276D03*
X1048100Y108500D03*
X1044700D03*
X1061000Y111000D03*
X1053000Y109500D03*
X1069711Y830301D03*
X1057112D03*
X1044514D03*
X1066511D03*
X1053912D03*
X1076010Y875176D03*
X1050813D03*
X1072810D03*
X1047613D03*
X1084000Y500D03*
X1083315Y36654D03*
X1082808Y30601D03*
X1092094Y30362D03*
X1080672Y9500D03*
X1084800Y9400D03*
X1083379Y40889D03*
X1083500Y25500D03*
X1082974Y14467D03*
X1105441Y54768D03*
X1100992Y52374D03*
X1078694Y43478D03*
X1077432Y64225D03*
X1103300Y73900D03*
X1103349Y70700D03*
X1088005Y46541D03*
X1088287Y55917D03*
X1096496Y51226D03*
X1107506Y830301D03*
X1094907D03*
X1082309D03*
X1104306D03*
X1091707D03*
X1079109D03*
X1101207Y875176D03*
X1088608D03*
X1110605D03*
X1098007D03*
X1085408D03*
X1112700Y80700D03*
X1114842Y83078D03*
X1122001Y126574D03*
Y136874D03*
X1135150Y137851D03*
X1122001Y133324D03*
X1141900Y137851D03*
X1122001Y130124D03*
X1138700Y137851D03*
X1126500Y222500D03*
X1135750Y228750D03*
X1143000Y242000D03*
X1132703Y830301D03*
X1120104D03*
X1142101D03*
X1129503D03*
X1116904D03*
X1139002Y875176D03*
X1126403D03*
X1113805D03*
X1135802D03*
X1123203D03*
X1154557Y138505D03*
X1145450Y137851D03*
X1161307Y138505D03*
X1158107D03*
X1170400Y144100D03*
X1150250Y228750D03*
X1147000Y242000D03*
X1151000D03*
X1157899Y830301D03*
X1145301D03*
X1176747D03*
X1154699D03*
X1164199Y875176D03*
X1151600D03*
X1160999D03*
X1148400D03*
X1182061Y142478D03*
X1190835Y137899D03*
X1199400Y142851D03*
X1178861Y142478D03*
X1187635Y137899D03*
X1196200Y142851D03*
X1206991Y156730D03*
X1203791D03*
X1201000Y417900D03*
X1196600Y416200D03*
X1192545Y830301D03*
X1179947D03*
X1189345D03*
X1199000Y867200D03*
X1186246Y875176D03*
X1195800Y867300D03*
X1183046Y875176D03*
X1214795Y142443D03*
X1234209Y142463D03*
X1242900Y137851D03*
X1225348Y137960D03*
X1231009Y142463D03*
X1239700Y137851D03*
X1222148Y137960D03*
X1242621Y153690D03*
X1236640Y830301D03*
X1224042D03*
X1233440D03*
X1220842D03*
X1242939Y875176D03*
X1230340D03*
X1239739D03*
X1227140D03*
X1277265Y137673D03*
X1274065D03*
X1273499Y151498D03*
X1273520Y148070D03*
X1261944Y145770D03*
X1258744D03*
X1251801Y144871D03*
X1255000Y317300D03*
X1270500Y335500D03*
X1272500Y350000D03*
X1275060Y345690D03*
X1277620Y349500D03*
X1264820Y349320D03*
X1249250Y390250D03*
X1269500Y397000D03*
X1273500Y400500D03*
X1258000Y421500D03*
X1274435Y830301D03*
X1261837D03*
X1249239D03*
X1271235D03*
X1258637D03*
X1246039D03*
X1268136Y875176D03*
X1255537D03*
X1277534D03*
X1264936D03*
X1252337D03*
X1303983Y22083D03*
X1304000Y44000D03*
Y67500D03*
Y90500D03*
X1286543Y141581D03*
X1296017Y137478D03*
X1283343Y141581D03*
X1292817Y137478D03*
X1290000Y271000D03*
X1308500Y262500D03*
X1311200Y256500D03*
X1293500Y271000D03*
X1312200Y275200D03*
X1303700Y289500D03*
X1288900Y304000D03*
X1283300Y302900D03*
X1309900Y292400D03*
X1310500Y285500D03*
X1281900Y346580D03*
X1282740Y350010D03*
X1293280Y345770D03*
X1289960Y349900D03*
X1299000Y347500D03*
X1311500Y391000D03*
X1310068Y394084D03*
X1297625Y382375D03*
X1296500Y386500D03*
X1290125Y382875D03*
X1289500Y386500D03*
X1282740Y383000D03*
X1282000Y386500D03*
X1301000Y618500D03*
X1300000Y637000D03*
X1297617Y677117D03*
X1286800Y671100D03*
X1297500Y664000D03*
X1310207D03*
X1297400Y651300D03*
X1290550D03*
X1302000Y695500D03*
X1302128Y685500D03*
X1307000Y686500D03*
X1304500Y698000D03*
X1301728Y714600D03*
X1312132Y684293D03*
X1310500Y723000D03*
X1291428Y726117D03*
X1306128Y732872D03*
X1302128D03*
X1312231Y830301D03*
X1287033D03*
X1309031D03*
X1283833D03*
X1305931Y875176D03*
X1293333D03*
X1280734D03*
X1302731D03*
X1290133D03*
X1339471Y139268D03*
X1316590Y147210D03*
X1317400Y143620D03*
X1340130Y145980D03*
X1331243Y182198D03*
X1322000Y276500D03*
X1322500Y266800D03*
X1333500Y290500D03*
X1317026Y304858D03*
X1314000Y286500D03*
X1313607Y664000D03*
X1327200Y661800D03*
X1331000Y662000D03*
X1326128Y674000D03*
X1340000D03*
X1317007Y664000D03*
X1334128Y674000D03*
X1337500Y698000D03*
X1322439Y697767D03*
X1315000Y686500D03*
X1329500Y684667D03*
X1321928Y683798D03*
X1318500Y684667D03*
X1339934Y683832D03*
X1336795Y685141D03*
X1326758Y686678D03*
X1314628Y733000D03*
X1315000Y723000D03*
X1333500D03*
X1334128Y732667D03*
X1325600Y722987D03*
X1342000Y732500D03*
X1337500Y723000D03*
X1340500Y742500D03*
X1338128Y732872D03*
X1330128Y732667D03*
X1337427Y830301D03*
X1324829D03*
X1346825D03*
X1334227D03*
X1321629D03*
X1343726Y875176D03*
X1331128D03*
X1318529D03*
X1340526D03*
X1327928D03*
X1315329D03*
X1359128Y167226D03*
X1355321Y172119D03*
X1354971Y167446D03*
X1365804Y185197D03*
X1355066Y275228D03*
X1348500Y276500D03*
X1361500Y273500D03*
X1352000Y276700D03*
X1352500Y267000D03*
X1369300Y259300D03*
X1355000Y286300D03*
X1364000Y280500D03*
X1351500Y675000D03*
X1350025Y830301D03*
X1381696Y173459D03*
X1387196Y174160D03*
X1382138Y184129D03*
X1385467Y180543D03*
G54D24*
X131700Y275700D03*
X125100Y282500D03*
X131700Y280000D03*
X300500Y715613D03*
G54D21*
X92990Y252362D03*
X116790D03*
X1301120Y173278D03*
Y183908D03*
G54D32*
X473231Y235560D03*
Y274930D03*
X487404Y255245D03*
G54D35*
X533010Y69803D03*
X535962Y64292D03*
X524151Y69803D03*
X527104Y64292D03*
X535962Y49331D03*
X527104D03*
X533010Y54843D03*
X524151D03*
X533010Y99725D03*
X535962Y94213D03*
X524151Y99725D03*
X527104Y94213D03*
X533010Y84764D03*
X535962Y79252D03*
X524151Y84764D03*
X527104Y79252D03*
X567458Y54843D03*
X570411Y49331D03*
Y64292D03*
X567458Y69803D03*
X541868D03*
X544821Y64292D03*
Y49331D03*
X541868Y54843D03*
X570411Y79252D03*
Y94213D03*
X567458Y84764D03*
Y99725D03*
X541868D03*
X544821Y94213D03*
X541868Y84764D03*
X544821Y79252D03*
X576317Y54843D03*
X585175D03*
X579269Y49331D03*
X588128D03*
X576317Y69803D03*
X585175D03*
X579269Y64292D03*
X588128D03*
X579269Y79252D03*
X588128D03*
X585175Y84764D03*
X576317D03*
Y99725D03*
X585175D03*
X579269Y94213D03*
X588128D03*
X619624Y54843D03*
X628482D03*
X622577Y49331D03*
X631435D03*
X619624Y69803D03*
X628482D03*
X622577Y64292D03*
X631435D03*
X610766Y54843D03*
X613718Y49331D03*
Y64292D03*
X610766Y69803D03*
X622577Y79252D03*
X631435D03*
X628482Y84764D03*
X619624D03*
Y99725D03*
X628482D03*
X622577Y94213D03*
X631435D03*
X613718Y79252D03*
Y94213D03*
X610766Y84764D03*
Y99725D03*
X662931Y54843D03*
X671789D03*
X665884Y49331D03*
X662931Y69803D03*
X671789D03*
X665884Y64292D03*
X654073Y54843D03*
X657025Y49331D03*
Y64292D03*
X654073Y69803D03*
X665884Y79252D03*
X671789Y84764D03*
X662931D03*
Y99725D03*
X671789D03*
X665884Y94213D03*
X657025Y79252D03*
Y94213D03*
X654073Y84764D03*
Y99725D03*
X674742Y49331D03*
Y64292D03*
Y79252D03*
Y94213D03*
X1135372Y69803D03*
X1144230D03*
X1138324Y64292D03*
X1126513Y69803D03*
X1129466Y64292D03*
X1138324Y49331D03*
X1129466D03*
X1144230Y54843D03*
X1135372D03*
X1126513D03*
X1135372Y99725D03*
X1144230D03*
X1138324Y94213D03*
X1126513Y99725D03*
X1129466Y94213D03*
X1135372Y84764D03*
X1144230D03*
X1138324Y79252D03*
X1126513Y84764D03*
X1129466Y79252D03*
X1178679Y54843D03*
Y69803D03*
X1169820Y54843D03*
X1172773Y49331D03*
Y64292D03*
X1169820Y69803D03*
X1147183Y64292D03*
Y49331D03*
X1178679Y84764D03*
Y99725D03*
X1172773Y79252D03*
Y94213D03*
X1169820Y84764D03*
Y99725D03*
X1147183Y94213D03*
Y79252D03*
X1187537Y54843D03*
X1181631Y49331D03*
X1190490D03*
X1187537Y69803D03*
X1181631Y64292D03*
X1190490D03*
X1181631Y79252D03*
X1190490D03*
X1187537Y84764D03*
Y99725D03*
X1181631Y94213D03*
X1190490D03*
X1221986Y54843D03*
X1230844D03*
X1224939Y49331D03*
X1233797D03*
X1221986Y69803D03*
X1230844D03*
X1224939Y64292D03*
X1233797D03*
X1213128Y54843D03*
X1216080Y49331D03*
Y64292D03*
X1213128Y69803D03*
X1224939Y79252D03*
X1233797D03*
X1230844Y84764D03*
X1221986D03*
Y99725D03*
X1230844D03*
X1224939Y94213D03*
X1233797D03*
X1216080Y79252D03*
Y94213D03*
X1213128Y84764D03*
Y99725D03*
X1265293Y54843D03*
X1274151D03*
X1268246Y49331D03*
X1277104D03*
X1265293Y69803D03*
X1274151D03*
X1268246Y64292D03*
X1277104D03*
X1256435Y54843D03*
X1259387Y49331D03*
Y64292D03*
X1256435Y69803D03*
X1268246Y79252D03*
X1277104D03*
X1274151Y84764D03*
X1265293D03*
Y99725D03*
X1274151D03*
X1268246Y94213D03*
X1277104D03*
X1259387Y79252D03*
Y94213D03*
X1256435Y84764D03*
Y99725D03*
G54D13*
X26977Y151614D03*
X96189D03*
G54D26*
X108200Y775800D03*
X112700Y775300D03*
Y770800D03*
X108200D03*
X103700D03*
Y775800D03*
Y766300D03*
X108200D03*
X112700D03*
X223000Y184000D03*
Y188500D03*
X225000Y192500D03*
X229200D03*
X243000Y176500D03*
X243500Y166500D03*
Y162000D03*
Y157000D03*
X243000Y181000D03*
Y186000D03*
X239900Y600100D03*
X240000Y608600D03*
Y604400D03*
X536081Y304376D03*
X536809Y298789D03*
X553563Y306108D03*
Y310608D03*
X557904Y327115D03*
X562123Y319158D03*
X553455Y314807D03*
X553463Y319108D03*
X557863D03*
X585515Y276459D03*
X583009Y264117D03*
X585351Y269292D03*
X587984Y246148D03*
X587980Y251975D03*
X589164Y264150D03*
X582738Y273300D03*
X587063Y257608D03*
X582976Y246148D03*
X583286Y251974D03*
X582682Y257614D03*
X589400Y308626D03*
X585737Y289608D03*
Y283108D03*
X582683Y279618D03*
X582411Y286589D03*
X582363Y293408D03*
X580563Y308608D03*
X583391Y298870D03*
X583282Y303091D03*
X704537Y221492D03*
X703600Y233700D03*
X677000Y299900D03*
X682063Y299108D03*
X683800Y295000D03*
X684063Y285908D03*
Y290408D03*
X712337Y207792D03*
X712137Y213292D03*
Y219392D03*
X716900Y233800D03*
X721400D03*
X730400D03*
X725900D03*
X735400D03*
X707900D03*
X712400D03*
X706800Y290700D03*
X718800Y291000D03*
X714300D03*
X707363Y298108D03*
X718863Y295908D03*
X714363D03*
X723300Y291000D03*
X732300D03*
X727800D03*
X723363Y295908D03*
X732363D03*
X727863D03*
X737300Y291000D03*
X921300Y74700D03*
X918100Y71900D03*
X929464Y49420D03*
X925022Y42909D03*
X929713Y44849D03*
X926500Y60050D03*
X930500Y57500D03*
X975086Y61900D03*
X970000Y61050D03*
X1171300Y215700D03*
X1166300D03*
X1175999D03*
X1168000Y280000D03*
X1173000D03*
X1177500D03*
X1190300Y215700D03*
X1185300D03*
X1208800D03*
X1203800D03*
X1180601D03*
X1199300D03*
X1194500D03*
X1187000Y280000D03*
X1192000D03*
X1205500D03*
X1210500D03*
X1182500D03*
X1201000D03*
X1196200D03*
X1214800Y215700D03*
X1360844Y210366D03*
X1355944Y210313D03*
X1351525Y207104D03*
X1351545Y202879D03*
Y198575D03*
X1378115Y189144D03*
X1374000Y192500D03*
Y188300D03*
Y196700D03*
X1378500Y198000D03*
X1378115Y193344D03*
X1351777Y227823D03*
X1360644Y223881D03*
X1350987Y236754D03*
X1351668Y232125D03*
X1355644Y223881D03*
X1351899Y219598D03*
X1351954Y215268D03*
X1354989Y239016D03*
X1350950Y241000D03*
X1349639Y211374D03*
X1349298Y223737D03*
X1355050Y247300D03*
X1350950Y246100D03*
X1382500Y193500D03*
Y188000D03*
G54D36*
X943111Y5908D03*
X935236D03*
X927361D03*
X919486D03*
X911616D03*
X943111Y13778D03*
X935236D03*
X927361D03*
X919486D03*
X911616D03*
X958856Y5908D03*
X950986D03*
X958856Y13778D03*
X950986D03*
G54D18*
X41603Y177598D03*
X65579D03*
X57587D03*
X49595D03*
X45559Y187598D03*
X37567D03*
X53551D03*
X73571Y177598D03*
X81563D03*
X77607Y187598D03*
X69615D03*
X85599D03*
G54D25*
X122700Y476100D03*
Y478400D03*
X122600Y473800D03*
Y471500D03*
X121673Y491672D03*
X130985Y504300D03*
X124822Y504271D03*
X127973Y504272D03*
X121673Y497973D03*
Y494822D03*
X118500Y504238D03*
X115373Y504271D03*
X127973Y510571D03*
X124823D03*
X121673D03*
X131121Y513721D03*
X121673D03*
X131121Y510570D03*
X127971Y513721D03*
X124821D03*
X127971Y494823D03*
X131122Y491674D03*
X127973Y488524D03*
X131122D03*
Y485374D03*
X121673Y504272D03*
X124823Y501122D03*
X121673D03*
X127973Y497973D03*
X124822Y488523D03*
X127973Y491674D03*
X124823Y497973D03*
Y491674D03*
X127973Y485374D03*
X124823Y494822D03*
X131121Y494823D03*
X127973Y501122D03*
Y529469D03*
X124823Y523170D03*
Y532617D03*
X124822Y545216D03*
X131122Y532618D03*
X124823Y535766D03*
X127973Y538918D03*
X127996Y535781D03*
X121673Y545215D03*
Y523170D03*
X131121Y529467D03*
Y520018D03*
X127971D03*
X131121Y523168D03*
X124822Y520019D03*
X121673Y520020D03*
X115374Y529467D03*
X118524D03*
X121673D03*
X124823D03*
X121673Y532617D03*
X124822Y538917D03*
X121673Y535766D03*
X127973Y523170D03*
X121673Y538916D03*
X126801Y574386D03*
X124900Y559638D03*
X124847Y550110D03*
X124900Y556462D03*
Y565990D03*
Y562814D03*
Y553286D03*
X122547Y561276D03*
Y554924D03*
Y567628D03*
X125072Y610945D03*
X125070Y598347D03*
X131370Y601496D03*
X118773Y601495D03*
X126646Y606400D03*
X115622Y614094D03*
Y601496D03*
X121922Y610945D03*
X128220Y614095D03*
X118773Y604645D03*
X125070Y614095D03*
X118773Y598345D03*
X118805Y614099D03*
X115623Y598345D03*
X118773Y610945D03*
X131369Y614095D03*
X118773Y589748D03*
X128221Y610945D03*
X121922Y588872D03*
X118773Y592048D03*
X125072Y620392D03*
X121921D03*
X140571Y491674D03*
X140570Y488523D03*
X162618Y485374D03*
X150020Y491674D03*
X156319Y485374D03*
X143721Y491674D03*
Y488524D03*
Y485374D03*
X140569Y494823D03*
X134270Y510571D03*
Y504272D03*
X146869Y494823D03*
X153168D03*
X159467D03*
X165768Y488524D03*
X153170Y491674D03*
X150020Y485374D03*
Y482225D03*
X146870Y485374D03*
Y488524D03*
X162618D03*
Y491674D03*
X134272D03*
X165768D03*
X134272Y488524D03*
Y485374D03*
X137421Y491674D03*
Y485374D03*
X140571D03*
X156318Y488523D03*
X156319Y491674D03*
X153169Y485374D03*
Y488524D03*
X159469Y491674D03*
Y488524D03*
Y485374D03*
X150020Y488524D03*
X137421D03*
X165766Y542066D03*
X143721Y532618D03*
X137421Y535768D03*
Y542066D03*
X134270Y538916D03*
X137421Y532618D03*
X134272Y542066D03*
Y535768D03*
X140570Y535767D03*
X137421Y538918D03*
X153188Y538899D03*
X162617Y535766D03*
X146869Y538954D03*
X146858Y535742D03*
X159449Y542048D03*
Y538898D03*
X159456Y532642D03*
X162617Y542066D03*
Y538916D03*
X149981Y538917D03*
X153132Y535767D03*
X149985Y535771D03*
X153194Y542078D03*
X153187Y532636D03*
X140571Y532618D03*
X143718Y538953D03*
X143686Y542070D03*
X146869Y529469D03*
X134270Y523170D03*
X153168Y529469D03*
X140569D03*
X134270Y516869D03*
X159467Y529469D03*
X134272Y532618D03*
X162618D03*
X165766Y538916D03*
X161280Y564000D03*
X147451Y551836D03*
Y549536D03*
X142951Y551036D03*
X161280Y566300D03*
X159537Y548256D03*
X147451Y556436D03*
X142951Y555636D03*
X160700Y551356D03*
X151989Y557138D03*
X161280Y556100D03*
X151989Y554838D03*
X161280Y558400D03*
X137669Y610945D03*
Y601495D03*
X140818D03*
X134521Y595196D03*
X134519Y614095D03*
X150269Y598347D03*
X156566Y614095D03*
X143968Y601495D03*
X140821Y614106D03*
X166016Y601496D03*
X159716Y610945D03*
Y614095D03*
Y595197D03*
X166016Y610944D03*
X162867Y614095D03*
X147115Y598360D03*
X150268Y601496D03*
X147141Y614096D03*
X143968Y588898D03*
X153417Y610945D03*
X159716Y604645D03*
X166015Y598345D03*
X147117Y610945D03*
X162865Y601495D03*
X150268Y610944D03*
X159716Y601495D03*
X140818Y610945D03*
X134520Y610944D03*
X153418Y592048D03*
X159716D03*
X134521Y598345D03*
X143968Y592048D03*
X147117Y601495D03*
X150251Y617226D03*
X134521Y617266D03*
X137671D03*
X140821D03*
X156566Y617244D03*
X159716D03*
X150351Y620436D03*
X181514Y479075D03*
X172065Y513721D03*
X175215D03*
X178365Y510571D03*
X175215D03*
X172065D03*
Y501122D03*
X178365Y507422D03*
X175215D03*
Y491674D03*
Y497973D03*
X172065Y491674D03*
X175215Y485374D03*
X175217Y482225D03*
X175215Y501122D03*
X178365D03*
X184664Y485372D03*
X172065Y494823D03*
X178365Y491674D03*
X181514Y488524D03*
X184664Y488522D03*
X175215Y494823D03*
X172065Y497973D03*
X178365Y494823D03*
X172065Y485374D03*
X172067Y482225D03*
X178365Y497973D03*
X172065Y504272D03*
X175216Y504271D03*
X172065Y507422D03*
X178365Y504272D03*
X168916Y510571D03*
Y504272D03*
X178365Y513721D03*
X172065Y488524D03*
X175216Y488523D03*
X178365Y485374D03*
Y488524D03*
X181514Y485374D03*
X178365Y520020D03*
X181514D03*
X172065Y535768D03*
Y526319D03*
X178365Y529469D03*
X175215D03*
X172065D03*
X175215Y523170D03*
X178365D03*
X175216Y535767D03*
X168916Y523170D03*
Y516870D03*
X184665Y520019D03*
X178365Y526319D03*
X175215D03*
Y532618D03*
X178365Y535768D03*
X172065Y532618D03*
X175215Y538918D03*
X168916Y535766D03*
X172065Y538918D03*
X168916Y542066D03*
Y538916D03*
X178365Y532618D03*
X874410Y139764D03*
Y131890D03*
Y120079D03*
Y124016D03*
Y163386D03*
Y155512D03*
Y147638D03*
Y202755D03*
Y206692D03*
Y194881D03*
Y183071D03*
Y242125D03*
Y238188D03*
Y230314D03*
Y222440D03*
Y214566D03*
Y257873D03*
Y253936D03*
Y249999D03*
Y246062D03*
X894095Y131890D03*
X898032Y139764D03*
Y131890D03*
Y135827D03*
X894095Y139764D03*
X905906Y124016D03*
Y120079D03*
Y116142D03*
X901969Y139764D03*
Y135827D03*
Y131890D03*
X886221Y139764D03*
X890158Y135827D03*
X886221Y131890D03*
X890158Y139764D03*
X894095Y135827D03*
X890158Y131890D03*
X878347Y135827D03*
Y116142D03*
X882284Y120079D03*
X886221Y116142D03*
X890158Y120079D03*
X894095Y116142D03*
X898032Y120079D03*
X901969Y116142D03*
X878347Y139764D03*
X882284Y135827D03*
X878347Y131890D03*
Y120079D03*
X882300Y124032D03*
X886221Y120079D03*
X890158Y124016D03*
X894095Y120079D03*
X898032Y124016D03*
X901969Y120079D03*
X905906Y139764D03*
Y135827D03*
Y131890D03*
X894095Y163386D03*
X898032D03*
Y167323D03*
Y171260D03*
Y175197D03*
X901969Y163386D03*
X905906D03*
X898032Y143701D03*
Y147638D03*
Y151575D03*
Y155512D03*
Y159449D03*
X886221Y171260D03*
X901969Y167323D03*
X905906D03*
X901969Y171260D03*
X905906D03*
X901969Y175197D03*
X905906D03*
X890158Y163386D03*
X894095Y167323D03*
Y175197D03*
X905906Y159449D03*
X901969D03*
X894095Y155512D03*
Y147638D03*
X882284Y167323D03*
X886221Y163386D03*
X882284D03*
X878347D03*
X886221Y159449D03*
X901969Y147638D03*
Y143701D03*
X890158Y159449D03*
X886221Y155512D03*
X890158Y151575D03*
X886221Y147638D03*
X890158Y143701D03*
X894095Y159449D03*
X890158Y155512D03*
X894095Y151575D03*
X890158Y147638D03*
X894095Y143701D03*
X878347Y159449D03*
Y151575D03*
Y143701D03*
X882284Y159449D03*
X878347Y155512D03*
X882284Y151575D03*
X878347Y147638D03*
X882284Y143701D03*
X905906Y155512D03*
Y151575D03*
Y147638D03*
Y143701D03*
X901969Y155512D03*
Y151575D03*
X905906Y183071D03*
X901969D03*
Y194881D03*
X905906D03*
X901969Y198818D03*
X905906D03*
X901969Y202755D03*
X905906D03*
X901969Y206692D03*
X905906D03*
X890158Y202755D03*
X898032Y206692D03*
X894095D03*
Y194881D03*
X901969Y179134D03*
X905906D03*
X901969Y190944D03*
X905906D03*
X894095Y183071D03*
X882284Y206692D03*
X886221Y202755D03*
X882284D03*
X878347D03*
X886221Y198818D03*
X882284Y194881D03*
X886221Y190944D03*
Y179134D03*
Y206692D03*
X890158Y198818D03*
X886221Y194881D03*
X890158Y190944D03*
X886221Y183071D03*
X890158Y179134D03*
Y206692D03*
X894095Y198818D03*
X890158Y194881D03*
X894095Y190944D03*
X890158Y183071D03*
X894095Y179134D03*
X878347Y198818D03*
Y190944D03*
Y206692D03*
X882284Y198818D03*
X878347Y194881D03*
X882284Y190944D03*
X878347Y183071D03*
X901969Y222440D03*
X905906D03*
X901969Y226377D03*
X905906D03*
Y234251D03*
X901969Y230314D03*
X905906D03*
X901969Y234251D03*
X894095Y222440D03*
X890158Y238188D03*
X894095Y242125D03*
Y230314D03*
X901969Y242125D03*
Y210629D03*
X905906D03*
X901969Y214566D03*
X905906D03*
X901969Y218503D03*
X905906D03*
X894095Y214566D03*
X886221Y226377D03*
X882284Y222440D03*
X886221Y242125D03*
X878347D03*
X886221Y238188D03*
X882284D03*
X878347D03*
X886221Y234251D03*
X882284Y230314D03*
X886221Y218503D03*
X882284Y214566D03*
X886221Y210629D03*
X890158Y234251D03*
X886221Y230314D03*
X890158Y226377D03*
X886221Y222440D03*
X890158Y218503D03*
X886221Y214566D03*
X890158Y210629D03*
X905906Y242125D03*
X898032D03*
X890158D03*
X882284D03*
X894095Y234251D03*
X890158Y230314D03*
X894095Y226377D03*
X890158Y222440D03*
X894095Y218503D03*
X890158Y214566D03*
X894095Y210629D03*
X878347Y234251D03*
Y226377D03*
Y218503D03*
Y210629D03*
X882284Y234251D03*
X878347Y230314D03*
X882284Y226377D03*
X878347Y222440D03*
X882284Y218503D03*
X878347Y214566D03*
X882284Y210629D03*
X901969Y253936D03*
X894095D03*
X890158Y249999D03*
X905906D03*
X898032D03*
X878347Y253936D03*
X886221D03*
X882284Y249999D03*
X905906Y246062D03*
X901969Y249999D03*
X898032Y246062D03*
X894095Y249999D03*
X890158Y246062D03*
X886221Y249999D03*
X882284Y246062D03*
X878347Y249999D03*
X901969Y246062D03*
X894095D03*
X886221D03*
X878347D03*
X905906Y257873D03*
X901969Y261810D03*
X898032Y257873D03*
X894095Y261810D03*
X890158Y257873D03*
X886221Y261810D03*
X882284Y257873D03*
X878347Y261810D03*
X905906Y253936D03*
X901969Y257873D03*
X898032Y253936D03*
X894095Y257873D03*
X890158Y253936D03*
X886221Y257873D03*
X882284Y253936D03*
X878347Y257873D03*
X909843Y131890D03*
X941339Y127953D03*
X913780Y131890D03*
X937402Y139764D03*
Y127953D03*
X941339Y139764D03*
X933465D03*
X921654Y135827D03*
X941339Y124016D03*
Y120079D03*
Y116142D03*
X937402Y124016D03*
X933465Y127953D03*
X929528Y124016D03*
X925591Y127953D03*
X921654Y124016D03*
X917717Y127953D03*
X909843Y135827D03*
X913780Y124016D03*
X909843Y127953D03*
X921654Y139764D03*
X929528D03*
X925591D03*
X921654Y131890D03*
X941339D03*
Y135827D03*
X933465Y131890D03*
Y135827D03*
X937402Y131890D03*
Y135827D03*
X929528Y131890D03*
Y135827D03*
X925591Y131890D03*
Y135827D03*
X909843Y120079D03*
X913780Y116142D03*
X917717Y120079D03*
X921654Y116142D03*
X925591Y120079D03*
X929528Y116142D03*
X933465Y120079D03*
X937402Y116142D03*
X909843Y124016D03*
X913780Y120079D03*
X917717Y124016D03*
X921654Y120079D03*
X925591Y124016D03*
X929528Y120079D03*
X933465Y124016D03*
X937402Y120079D03*
X913780Y135827D03*
X917717Y139764D03*
Y131890D03*
Y135827D03*
X909843Y139764D03*
X937402Y155512D03*
X941339Y151575D03*
Y155512D03*
X929528Y159449D03*
X913780Y143701D03*
Y159449D03*
X937402D03*
X913780Y147638D03*
X917717Y159449D03*
X913780Y155512D03*
Y151575D03*
X941339Y175197D03*
Y167323D03*
X933465Y175197D03*
X937402Y171260D03*
X933465Y167323D03*
X937402Y163386D03*
X929528Y171260D03*
X925591Y175197D03*
X921654Y163386D03*
X925591Y167323D03*
X917717D03*
X921654Y171260D03*
X917717Y175197D03*
X929528Y163386D03*
X941339Y159449D03*
X937402Y151575D03*
X933465Y159449D03*
X925591D03*
X921654Y147638D03*
X909843Y163386D03*
X913780D03*
X909843Y167323D03*
X913780D03*
X909843Y171260D03*
X913780D03*
X909843Y175197D03*
X913780D03*
X909843Y147638D03*
X933465Y151575D03*
Y155512D03*
X921654Y151575D03*
X929528D03*
Y155512D03*
X925591Y143701D03*
Y147638D03*
Y155512D03*
X909843Y159449D03*
Y143701D03*
Y155512D03*
X941339Y143701D03*
Y147638D03*
X933465Y143701D03*
Y147638D03*
X937402Y143701D03*
Y147638D03*
X929528Y143701D03*
Y147638D03*
X917717Y155512D03*
Y151575D03*
Y143701D03*
Y147638D03*
X921654Y155512D03*
X917717Y179134D03*
X925591Y194881D03*
X921654Y198818D03*
X917717Y202755D03*
X937402Y206692D03*
X941339Y202755D03*
Y194881D03*
X937402Y198818D03*
X933465Y202755D03*
X929528Y206692D03*
X933465Y194881D03*
X929528Y198818D03*
X925591Y202755D03*
X921654Y206692D03*
X917717Y194881D03*
X937402Y179134D03*
X933465Y183071D03*
X929528Y190944D03*
Y179134D03*
X925591Y183071D03*
X921654Y179134D03*
X937402Y190944D03*
X917717Y183071D03*
X921654Y190944D03*
X909843Y194881D03*
X913780D03*
X909843Y198818D03*
X913780D03*
X909843Y202755D03*
X913780D03*
X909843Y206692D03*
X913780D03*
X909843Y179134D03*
X913780D03*
X909843Y183071D03*
Y190944D03*
X913780D03*
X917717Y214566D03*
Y222440D03*
Y226377D03*
X921654Y222440D03*
Y226377D03*
X917717Y230314D03*
Y234251D03*
X921654Y230314D03*
Y234251D03*
X925591Y230314D03*
Y222440D03*
X933465D03*
X941339D03*
X937402Y226377D03*
X929528D03*
X941339Y238188D03*
Y230314D03*
X937402Y242125D03*
Y234251D03*
X933465Y238188D03*
Y230314D03*
X929528Y242125D03*
Y234251D03*
X925591Y238188D03*
X921654Y242125D03*
X929528Y214566D03*
X933465Y210629D03*
X925591D03*
X917717D03*
X921654Y218503D03*
X925591D03*
X929528D03*
X933465D03*
X937402D03*
X941339D03*
X921654Y214566D03*
X917717Y218503D03*
X937402Y214566D03*
X913780Y226377D03*
X909843Y222440D03*
X913780D03*
X909843Y226377D03*
Y230314D03*
Y234251D03*
X913780Y230314D03*
Y234251D03*
Y242125D03*
X909843D03*
Y214566D03*
Y210629D03*
X913780D03*
X909843Y218503D03*
X913780D03*
X941339Y242125D03*
X933465D03*
X925591D03*
X917717D03*
X937402Y253936D03*
X929528D03*
X921654D03*
X941339Y249999D03*
X933465D03*
X925591D03*
X917717D03*
X913780Y253936D03*
X909843Y261810D03*
Y257873D03*
Y253936D03*
Y249999D03*
Y246062D03*
X941339D03*
X937402Y249999D03*
X933465Y246062D03*
X929528Y249999D03*
X925591Y246062D03*
X921654Y249999D03*
X917717Y246062D03*
X913780Y249999D03*
X937402Y246062D03*
X929528D03*
X921654D03*
X913780D03*
X941339Y257873D03*
X937402Y261810D03*
X933465Y257873D03*
X929528Y261810D03*
X925591Y257873D03*
X921654Y261810D03*
X917717Y257873D03*
X913780Y261810D03*
X941339Y253936D03*
X937402Y257873D03*
X933465Y253936D03*
X929528Y257873D03*
X925591Y253936D03*
X921654Y257873D03*
X917717Y253936D03*
X913780Y257873D03*
X953149Y127953D03*
X949212D03*
Y139764D03*
X957086Y127953D03*
X964960D03*
X972834D03*
X957086Y139764D03*
X953149Y135827D03*
X968897Y139764D03*
X953149Y124016D03*
Y120079D03*
Y116142D03*
X972834Y124016D03*
X968897Y127953D03*
X964960Y124016D03*
X961023Y127953D03*
X957086Y124016D03*
X972834Y139764D03*
X953149D03*
Y131890D03*
X957086D03*
X964960D03*
X961023Y139764D03*
Y131890D03*
Y135827D03*
X957086D03*
Y116142D03*
X961023Y120079D03*
X964960Y116142D03*
X968897Y120079D03*
X972834Y116142D03*
X957086Y120079D03*
X961023Y124016D03*
X964960Y120079D03*
X968897Y124016D03*
X972834Y120079D03*
Y135827D03*
Y131890D03*
X964960Y135827D03*
Y139764D03*
X968897Y135827D03*
Y131890D03*
X949212Y155512D03*
X953149Y163386D03*
X968897Y151575D03*
X964960Y159449D03*
X957086D03*
X953149Y151575D03*
X949212Y159449D03*
X972834D03*
X953149Y167323D03*
X957086Y163386D03*
X949212Y171260D03*
Y163386D03*
X972834Y171260D03*
X968897Y175197D03*
X972834Y163386D03*
X968897Y167323D03*
X964960Y171260D03*
X961023Y175197D03*
Y167323D03*
X964960Y163386D03*
X953149Y175197D03*
X957086Y171260D03*
X953149Y159449D03*
X949212Y151575D03*
X972834Y147638D03*
X968897Y159449D03*
X961023D03*
Y147638D03*
X972834Y151575D03*
X957086Y143701D03*
X961023D03*
X957086Y151575D03*
Y147638D03*
Y155512D03*
X953149Y143701D03*
Y155512D03*
X949212Y143701D03*
Y147638D03*
X964960Y143701D03*
X961023Y155512D03*
Y151575D03*
X964960Y155512D03*
Y151575D03*
X968897Y155512D03*
X964960Y147638D03*
X968897D03*
Y143701D03*
X972834D03*
Y155512D03*
X964960Y198818D03*
X961023Y202755D03*
X957086Y206692D03*
X968897Y194881D03*
X953149D03*
X949212Y198818D03*
Y206692D03*
X953149Y202755D03*
X961023Y194881D03*
X957086Y198818D03*
X972834Y206692D03*
Y198818D03*
X968897Y202755D03*
X964960Y206692D03*
X972834Y190944D03*
X964960Y179134D03*
X961023Y183071D03*
X957086Y190944D03*
X953149Y183071D03*
X957086Y179134D03*
X949212D03*
X964960Y190944D03*
X968897Y183071D03*
X972834Y179134D03*
Y238188D03*
Y222440D03*
Y226377D03*
Y230314D03*
Y234251D03*
X968897Y230314D03*
Y222440D03*
X953149D03*
X961023D03*
X972834Y242125D03*
X949212Y226377D03*
X964960D03*
X957086D03*
X953149Y238188D03*
Y230314D03*
X949212Y242125D03*
Y234251D03*
X968897Y238188D03*
X964960Y242125D03*
Y234251D03*
X961023Y238188D03*
Y230314D03*
X957086Y242125D03*
Y234251D03*
X949212Y214566D03*
X953149Y210629D03*
X968897D03*
X964960Y214566D03*
X972834Y218503D03*
X949212D03*
X953149D03*
X957086Y214566D03*
X961023Y210629D03*
X972834Y214566D03*
X957086Y218503D03*
X961023D03*
X964960D03*
X968897D03*
Y242125D03*
X961023D03*
X953149D03*
X972834Y253936D03*
X949212Y261810D03*
Y257873D03*
Y253936D03*
X964960D03*
X957086D03*
X953149Y249999D03*
X949212D03*
Y246062D03*
X968897Y249999D03*
X961023D03*
X972834D03*
X968897Y246062D03*
X964960Y249999D03*
X961023Y246062D03*
X957086Y249999D03*
X953149Y246062D03*
X972834D03*
X964960D03*
X957086D03*
X972834Y261810D03*
X968897Y257873D03*
X964960Y261810D03*
X961023Y257873D03*
X957086Y261810D03*
X953149Y257873D03*
X972834D03*
X968897Y253936D03*
X964960Y257873D03*
X961023Y253936D03*
X957086Y257873D03*
X953149Y253936D03*
X992519Y139764D03*
X996456D03*
Y131890D03*
Y135827D03*
X1000393Y131890D03*
X980708Y127953D03*
Y139764D03*
X1008267Y135827D03*
Y127953D03*
Y124016D03*
X984645Y135827D03*
X1000393Y139764D03*
X992519Y127953D03*
Y124016D03*
X988582Y127953D03*
Y124016D03*
Y120079D03*
Y116142D03*
X984645Y127953D03*
X980708Y124016D03*
X996456Y127953D03*
X1000393Y124016D03*
Y127953D03*
X1004330D03*
X976771D03*
X980708Y135827D03*
Y131890D03*
X1008267Y139764D03*
X976771Y120079D03*
X980708Y116142D03*
X984645Y120079D03*
X1008267Y131890D03*
X1004330Y135827D03*
Y139764D03*
X976771Y124016D03*
X980708Y120079D03*
X984645Y124016D03*
X1004330Y131890D03*
X1000393Y135827D03*
X992519Y115742D03*
X996456Y120079D03*
X1000393Y116142D03*
X1004330Y120079D03*
X1008267Y116142D03*
X992519Y120079D03*
X996456Y124016D03*
X1000393Y120079D03*
X1004330Y124016D03*
X1008267Y120079D03*
X988582Y139764D03*
Y135827D03*
X984645Y131890D03*
X976771D03*
Y139764D03*
X988582Y131890D03*
X984645Y139764D03*
X976771Y135827D03*
X996456Y163386D03*
X1000393D03*
X996456Y167323D03*
Y171260D03*
Y175197D03*
X992519Y163386D03*
X988582D03*
X980708Y175197D03*
X996456Y143701D03*
Y147638D03*
Y151575D03*
Y155512D03*
Y159449D03*
X1008267Y163386D03*
Y171260D03*
Y159449D03*
Y143701D03*
Y151575D03*
X980708Y163386D03*
X984645D03*
X988582Y167323D03*
X992519D03*
X980708D03*
X984645D03*
X988582Y171260D03*
X992519D03*
X980708D03*
X984645D03*
X988582Y175197D03*
X992519D03*
X984645D03*
X1000393Y167323D03*
X1004330Y163386D03*
X1000393Y175197D03*
X988582Y159449D03*
X992519D03*
X984645Y147638D03*
X1000393D03*
Y155512D03*
X976771Y167323D03*
Y175197D03*
X980708Y159449D03*
Y155512D03*
X976771Y151575D03*
X1004330Y143701D03*
X1008267Y147638D03*
X1004330Y151575D03*
X1008267Y155512D03*
X1004330Y159449D03*
X1008267Y167323D03*
X1004330Y171260D03*
X1008267Y175197D03*
X1000393Y143701D03*
X1004330Y147638D03*
X1000393Y151575D03*
X1004330Y155512D03*
X1000393Y159449D03*
X1004330Y167323D03*
X1000393Y171260D03*
X1004330Y175197D03*
X988582Y147638D03*
Y143701D03*
X984645Y155512D03*
Y151575D03*
Y143701D03*
X988582Y151575D03*
X976771Y147638D03*
X980708Y143701D03*
X976771Y155512D03*
X980708Y147638D03*
Y151575D03*
X976771Y159449D03*
Y143701D03*
X996456Y194881D03*
Y198818D03*
Y202755D03*
X1000393D03*
X996456Y179134D03*
Y183071D03*
Y190944D03*
X992519Y183071D03*
X988582D03*
X976771Y179134D03*
X980708Y183071D03*
X1008267Y202755D03*
Y198818D03*
Y190944D03*
Y179134D03*
X980708Y198818D03*
X988582Y194881D03*
X992519D03*
X980708D03*
X984645D03*
X988582Y198818D03*
X992519D03*
X984645D03*
X988582Y202755D03*
X992519D03*
X980708D03*
X984645D03*
X988582Y206692D03*
X992519D03*
X980708D03*
X984645D03*
X1000393D03*
X996456D03*
X1004330Y202755D03*
X1000393Y194881D03*
X988582Y179134D03*
X992519D03*
X988582Y190944D03*
X992519D03*
X980708D03*
X984645D03*
X980708Y179134D03*
X984645D03*
Y183071D03*
X1000393D03*
X976771Y202755D03*
Y194881D03*
Y183071D03*
X1004330Y179134D03*
X1008267Y183071D03*
X1004330Y190944D03*
X1008267Y194881D03*
X1004330Y198818D03*
X1008267Y206692D03*
X1000393Y179134D03*
X1004330Y183071D03*
X1000393Y190944D03*
X1004330Y194881D03*
X1000393Y198818D03*
X1004330Y206692D03*
X992519Y238188D03*
X988582D03*
X984645D03*
X980708D03*
X1000393D03*
X996456D03*
Y234251D03*
Y230314D03*
Y226377D03*
Y222440D03*
Y218503D03*
Y214566D03*
Y210629D03*
X976771Y238188D03*
Y214566D03*
X980708D03*
X1008267Y226377D03*
Y242125D03*
Y238188D03*
Y234251D03*
Y218503D03*
Y210629D03*
X1000393Y222440D03*
X988582D03*
X992519D03*
X980708D03*
X984645D03*
X988582Y226377D03*
X992519D03*
X984645D03*
X980708D03*
X988582Y230314D03*
X992519D03*
Y234251D03*
X980708Y230314D03*
Y234251D03*
X984645Y230314D03*
Y234251D03*
X988582D03*
X1000393Y230314D03*
X1004330Y238188D03*
X1000393Y242125D03*
X980708D03*
X984645D03*
X992519D03*
X984645Y214566D03*
X988582Y210629D03*
X992519D03*
X980708D03*
X984645D03*
X988582Y214566D03*
X992519D03*
X988582Y218503D03*
X992519D03*
X980708D03*
X984645D03*
X1000393Y214566D03*
X976771Y222440D03*
Y226377D03*
Y230314D03*
Y234251D03*
Y210629D03*
Y218503D03*
X1004330Y210629D03*
X1008267Y214566D03*
X1004330Y218503D03*
X1008267Y222440D03*
X1004330Y226377D03*
X1008267Y230314D03*
X1004330Y234251D03*
X1000393Y210629D03*
X1004330Y214566D03*
X1000393Y218503D03*
X1004330Y222440D03*
X1000393Y226377D03*
X1004330Y230314D03*
X1000393Y234251D03*
X1004330Y242125D03*
X996456D03*
X988582D03*
X976771D03*
X1008267Y253936D03*
X980708D03*
X984645D03*
Y257873D03*
Y261810D03*
X992519Y253936D03*
X1000393D03*
X984645Y246062D03*
Y249999D03*
X988582D03*
X996456D03*
X1004330D03*
X976771D03*
X1008267D03*
X1004330Y246062D03*
X1000393Y249999D03*
X996456Y246062D03*
X992519Y249999D03*
X988582Y246062D03*
X980708Y249999D03*
X976771Y246062D03*
X1008267D03*
X1000393D03*
X992519D03*
X980708D03*
X1008267Y261810D03*
X1004330Y257873D03*
X1000393Y261810D03*
X996456Y257873D03*
X992519Y261810D03*
X988582Y257873D03*
X980708Y261810D03*
X976771Y257873D03*
X1008267D03*
X1004330Y253936D03*
X1000393Y257873D03*
X996456Y253936D03*
X992519Y257873D03*
X988582Y253936D03*
X980708Y257873D03*
X976771Y253936D03*
X1021751Y117469D03*
X1012204Y131890D03*
Y139764D03*
Y127953D03*
X1016141Y124016D03*
X1020078Y127953D03*
X1016141D03*
X1020078Y139764D03*
X1012204Y120079D03*
X1016141Y116142D03*
X1020078Y120079D03*
Y131890D03*
X1016141Y135827D03*
Y139764D03*
X1012204Y124016D03*
X1016141Y120079D03*
X1023278D03*
X1016141Y131890D03*
X1012204Y135827D03*
Y167323D03*
Y163386D03*
X1016141D03*
X1020078D03*
X1012204Y175197D03*
Y147638D03*
Y155512D03*
X1016141Y143701D03*
X1020078Y147638D03*
X1016141Y151575D03*
X1020078Y155512D03*
X1016141Y159449D03*
X1020078Y167323D03*
X1016141Y171260D03*
X1020078Y175197D03*
X1012204Y143701D03*
X1016141Y147638D03*
X1012204Y151575D03*
X1016141Y155512D03*
X1012204Y159449D03*
X1016141Y167323D03*
X1012204Y171260D03*
X1016141Y175197D03*
X1012204Y206692D03*
Y202755D03*
Y194881D03*
X1016141Y202755D03*
X1020078D03*
X1012204Y183071D03*
X1016141Y179134D03*
X1020078Y183071D03*
X1016141Y190944D03*
X1020078Y194881D03*
X1016141Y198818D03*
X1020078Y206692D03*
X1012204Y179134D03*
X1016141Y183071D03*
X1012204Y190944D03*
X1016141Y194881D03*
X1012204Y198818D03*
X1016141Y206692D03*
X1012204Y222440D03*
Y238188D03*
Y230314D03*
X1016141Y242125D03*
X1020078D03*
X1016141Y238188D03*
X1020078D03*
X1012204Y214566D03*
Y242125D03*
X1016141Y210629D03*
X1020078Y214566D03*
X1016141Y218503D03*
X1020078Y222440D03*
X1016141Y226377D03*
X1020078Y230314D03*
X1016141Y234251D03*
X1012204Y210629D03*
X1016141Y214566D03*
X1012204Y218503D03*
X1016141Y222440D03*
X1012204Y226377D03*
X1016141Y230314D03*
X1012204Y234251D03*
X1020078Y257873D03*
X1016141Y253936D03*
X1020078D03*
X1012204Y249999D03*
X1020078D03*
Y246062D03*
X1016141Y249999D03*
X1012204Y246062D03*
X1016141D03*
Y261810D03*
X1012204Y257873D03*
X1016141D03*
X1012204Y253936D03*
G54D23*
X134251Y153543D03*
X151968D03*
X144094D03*
X1027722Y-9125D03*
X1054494D03*
G54D31*
X476614Y167493D03*
Y162493D03*
Y157493D03*
G54D28*
X193900Y274372D03*
X183900D03*
X203900D03*
X302500Y207200D03*
X292500D03*
X326200D03*
X336200D03*
X312500D03*
X346200D03*
X465485Y200680D03*
Y190680D03*
Y180680D03*
X488462Y180761D03*
Y190761D03*
Y200761D03*
X526215Y184000D03*
X511742Y215594D03*
X521742D03*
X531742D03*
X565585Y184000D03*
X772300Y16200D03*
X762300D03*
X752300D03*
X785300Y16100D03*
X795300D03*
X805300D03*
X819291Y265354D03*
Y285354D03*
X1075197Y92126D03*
Y112126D03*
X1348785Y161642D03*
X1323195D03*
G54D12*
X31977Y126614D03*
Y116614D03*
X91189Y126614D03*
Y116614D03*
Y136614D03*
G54D20*
X58400Y271800D03*
X57500Y263300D03*
X63700Y257300D03*
X63800Y267100D03*
X44426Y267408D03*
X59173Y288186D03*
X71094Y285981D03*
X77964Y285670D03*
X68429Y288212D03*
X75450Y694150D03*
X130900Y714300D03*
Y710800D03*
X107950Y687650D03*
X111400Y741800D03*
Y718300D03*
X118060Y743460D03*
X136400Y738300D03*
Y721800D03*
X623498Y140671D03*
G54D11*
X18577Y107902D03*
X5500Y119571D03*
Y139571D03*
Y159571D03*
X22000Y167200D03*
X5500Y179571D03*
Y199571D03*
X26500Y199500D03*
X21900Y199700D03*
X21800Y188100D03*
X5500Y219571D03*
Y239571D03*
X23100Y224500D03*
X28400Y262800D03*
X18000Y271600D03*
X5500Y259571D03*
X18000Y289400D03*
X28200Y296100D03*
X5500Y279571D03*
Y299571D03*
X26300Y317600D03*
X21400Y327900D03*
Y341000D03*
X5500Y339571D03*
Y319571D03*
X21400Y354000D03*
X22900Y365300D03*
X5500Y359571D03*
Y399571D03*
Y379571D03*
X31324Y410800D03*
X5500Y419571D03*
Y439571D03*
Y479571D03*
Y459571D03*
Y499571D03*
Y519571D03*
Y539571D03*
Y579571D03*
Y559571D03*
Y599571D03*
Y639571D03*
Y619571D03*
Y679571D03*
Y659571D03*
Y699571D03*
X27125Y695275D03*
X18250Y749250D03*
X5500Y719571D03*
Y739571D03*
Y779571D03*
Y759571D03*
Y799571D03*
X10020Y835051D03*
X30020D03*
X5500Y819571D03*
X31400Y209190D03*
X46760Y209157D03*
X63250Y205050D03*
X42800Y200100D03*
X44400Y216600D03*
X34900Y216800D03*
X59800Y211800D03*
X50200Y212000D03*
X31500Y224400D03*
X44029Y272572D03*
X35150Y273250D03*
X42900Y284500D03*
X58730Y299508D03*
X35150Y284350D03*
X49100Y328300D03*
X39600Y317600D03*
X58990Y342700D03*
X34800Y321200D03*
X54600Y328600D03*
X31500Y366900D03*
X48512Y356488D03*
X49300Y346700D03*
X43262Y357062D03*
X44866Y378634D03*
X55907Y350673D03*
X60610Y381665D03*
X47132Y444399D03*
X48000Y426000D03*
Y422500D03*
Y429500D03*
X57800Y420700D03*
X31500Y447000D03*
X64200Y534500D03*
X53500Y690200D03*
X60650Y694050D03*
X50020Y835051D03*
X96584Y195100D03*
X78050Y196300D03*
X82676Y208785D03*
X67600Y209500D03*
X92859Y226659D03*
X87978Y226596D03*
X78508Y232693D03*
X72934Y232675D03*
X95200Y210800D03*
X85600D03*
X80600Y216700D03*
X71000Y216600D03*
X88276Y232700D03*
X94600Y277100D03*
X93672Y270153D03*
X71870Y257120D03*
X75400Y309700D03*
X78121Y325870D03*
X73721D03*
X70210Y342700D03*
X77290Y344212D03*
X86511Y344200D03*
X66400Y334500D03*
X75256Y370303D03*
X70591Y359309D03*
X71794Y377639D03*
X92580Y410761D03*
X79600Y399200D03*
X95223Y385704D03*
X92752Y434193D03*
X91370Y445394D03*
X70700Y443244D03*
X77859Y429879D03*
X72533Y416996D03*
X79164Y426221D03*
X91311Y456609D03*
X89400Y470400D03*
X77681Y499033D03*
X77413Y506468D03*
X90500Y580100D03*
X81000Y579000D03*
X95252Y571638D03*
X70800Y559895D03*
X77400Y559000D03*
X77250Y562750D03*
X77400Y577000D03*
X71400Y578300D03*
X87555Y561085D03*
X87200Y574250D03*
X90500Y587000D03*
X80300Y596100D03*
X69258Y603000D03*
X82000Y592500D03*
X78300Y634250D03*
X94860Y628750D03*
X75800Y681900D03*
X69700Y690300D03*
X89825Y692875D03*
X79250Y716050D03*
X91800Y716100D03*
X66700Y713500D03*
X70020Y835051D03*
X90020D03*
X118577Y107902D03*
X104000Y128330D03*
X114364Y122054D03*
X118500Y176500D03*
Y173000D03*
X100900Y173800D03*
X116000Y207000D03*
Y202000D03*
X118500Y188500D03*
X116000Y192000D03*
Y196500D03*
X118500Y185000D03*
Y181000D03*
X104100Y194600D03*
X103700Y200800D03*
X116000Y211500D03*
X113300Y276600D03*
X127330Y248029D03*
X112764Y264218D03*
X109810Y310358D03*
X113000Y280500D03*
X113100Y284100D03*
X109972Y305968D03*
X112217Y296435D03*
X106400Y312200D03*
X99128Y366961D03*
X108200Y378656D03*
X126800Y362500D03*
X108484Y348377D03*
X108453Y385164D03*
X100924Y409968D03*
X105303Y419497D03*
X116173Y422379D03*
X107844Y414785D03*
X99749Y443671D03*
X99818Y437908D03*
X127925Y428093D03*
X115500Y454700D03*
X111500D03*
X103500D03*
X118524Y491672D03*
X124823Y542067D03*
X127973Y532618D03*
Y542067D03*
X104461Y571715D03*
X100140Y559260D03*
X99460Y566200D03*
X126869Y577770D03*
X122547Y564452D03*
Y558100D03*
Y551748D03*
X121601Y574686D03*
X104400Y590300D03*
X131369Y610945D03*
X115622Y604646D03*
X121911Y614076D03*
X102000Y599000D03*
X131369Y588898D03*
X121922Y592048D03*
X118771Y595196D03*
X121922Y617244D03*
X128221D03*
X120351Y633500D03*
X126851Y633449D03*
X116551Y644936D03*
X131369Y617244D03*
X118771D03*
X125070D03*
X131051Y656436D03*
X119051Y653906D03*
X109800Y681900D03*
X132200Y761300D03*
Y756300D03*
X138577Y107902D03*
X158577D03*
X149380Y176010D03*
X163000Y211500D03*
X157200Y241400D03*
X153000Y225000D03*
X134120Y267630D03*
X157300Y259900D03*
X157400Y254000D03*
X157300Y246500D03*
X139286Y311214D03*
X158170Y314302D03*
X162670D03*
X153670D03*
X156170Y318302D03*
X160670D03*
X143000Y342900D03*
X155891Y339730D03*
X140500Y390500D03*
X145500Y385500D03*
X158800Y406255D03*
X143000Y388000D03*
X142608Y403594D03*
X157550Y399100D03*
X139019Y443177D03*
X159540Y445692D03*
X146165Y444876D03*
X149838Y446190D03*
X150431Y420306D03*
X133000Y454700D03*
X146870Y491674D03*
Y482225D03*
X150020Y510571D03*
X153169D03*
X146870D03*
X153169Y513721D03*
X146870D03*
X150020D03*
X146870Y516870D03*
X150020D03*
X153169D03*
X151989Y552538D03*
X147451Y554136D03*
X142951Y553336D03*
X161280Y553800D03*
Y561700D03*
X143968Y614095D03*
X143967Y610945D03*
X137669Y604645D03*
X162865Y595196D03*
Y604645D03*
X156566Y610945D03*
X159716Y598345D03*
X153417Y614095D03*
X150269D03*
X153418Y595197D03*
X162865Y610945D03*
X137661Y614096D03*
X137670Y595197D03*
X147143Y595184D03*
X165851Y630651D03*
X137551Y629849D03*
X149851Y631251D03*
X155851Y631051D03*
X160851Y630651D03*
X150069Y640500D03*
X150280Y636620D03*
X150600Y648300D03*
X150409Y643884D03*
X143969Y617244D03*
X162881Y617266D03*
X153417Y617244D03*
X161200Y723900D03*
X150200Y729400D03*
X153700D03*
X157700Y748900D03*
X154000Y779000D03*
X143000Y784500D03*
X146500D03*
X150500Y804000D03*
X138500Y835000D03*
X137600Y839500D03*
X141100Y824500D03*
X141000Y830700D03*
X145900Y824400D03*
X142500Y862500D03*
Y867500D03*
Y872500D03*
X138500Y869500D03*
Y875200D03*
X141000Y877700D03*
X145500D03*
X149700D03*
X142500Y856500D03*
X159449Y878276D03*
X178577Y107902D03*
X181738Y122711D03*
X171500Y207500D03*
Y202500D03*
X193400Y192900D03*
X167000Y211500D03*
X172450Y211050D03*
X180850Y285650D03*
X176098Y444355D03*
X173471Y454700D03*
X184664Y516869D03*
X172065Y523170D03*
Y520020D03*
X175216Y520019D03*
X197500Y577300D03*
X198600Y599750D03*
Y588750D03*
X181371Y601636D03*
X193500Y700000D03*
X182500Y705500D03*
X186000D03*
X190000Y725000D03*
X177700Y723900D03*
X182860Y742240D03*
X181200Y748900D03*
X190000Y780500D03*
X170500Y779000D03*
X193500Y755500D03*
X182500Y761000D03*
X186000D03*
X175660Y797340D03*
X174000Y804000D03*
X195000Y824090D03*
X188572Y832186D03*
X196474Y832178D03*
X196000Y868700D03*
X176771Y878276D03*
X195669D03*
X168898Y878200D03*
X185500D03*
X227669Y5500D03*
X210028Y12605D03*
Y32605D03*
Y52605D03*
Y72605D03*
X226533Y72591D03*
X228121Y63589D03*
X210028Y92605D03*
X227989Y83589D03*
X228500Y138100D03*
X223750Y141370D03*
X218725Y138175D03*
X224500Y170500D03*
Y174700D03*
Y166300D03*
X213282Y188452D03*
X202892Y188441D03*
X224500Y178900D03*
X205013Y192596D03*
X218102Y334880D03*
X218070Y340244D03*
X219763Y472187D03*
X216600Y496550D03*
X217800Y512500D03*
X221000Y541300D03*
X217500Y519800D03*
Y529250D03*
X216300Y550500D03*
X216278Y567341D03*
X216090Y593937D03*
X210000Y700000D03*
X213500Y725000D03*
X215160Y718340D03*
X227409Y775903D03*
X233000D03*
X213500Y780500D03*
X210000Y755500D03*
X215160Y773840D03*
X203124Y824090D03*
X233650Y827374D03*
X208700Y828000D03*
X201641Y827947D03*
X214380Y827374D03*
X221052D03*
X226978D03*
X201500Y868700D03*
X233464Y878276D03*
X208267D03*
X201969D03*
X220866D03*
X214567D03*
X227166D03*
X247669Y5500D03*
X258159Y73589D03*
X257851Y63589D03*
X257769Y83589D03*
X264500Y142750D03*
X259500Y138500D03*
X254500Y142750D03*
X259500Y143250D03*
Y147750D03*
Y160750D03*
Y156250D03*
X264397Y160977D03*
X264500Y157250D03*
Y153750D03*
Y150250D03*
Y146250D03*
X259500Y152000D03*
X254500Y161250D03*
Y157250D03*
Y153750D03*
Y150250D03*
Y146250D03*
X261500Y173500D03*
X253000Y166500D03*
X258700D03*
X262900D03*
X239600Y142900D03*
X261500Y179000D03*
Y184500D03*
X261000Y190500D03*
X258225Y193963D03*
X266500Y184500D03*
Y190500D03*
X241231Y238869D03*
X236300Y227280D03*
X247500Y233750D03*
X267300Y300600D03*
Y328640D03*
X257340Y338640D03*
X260929Y345571D03*
X248930Y358000D03*
X260646Y499181D03*
X256855Y499154D03*
X265019Y497483D03*
X255487Y512454D03*
X249700Y525737D03*
Y521250D03*
X252238Y574238D03*
X266100Y614400D03*
X265850Y606400D03*
X248500Y583000D03*
X260100Y647400D03*
X259300Y632400D03*
Y639300D03*
X250500Y642500D03*
X265900Y622400D03*
X238100Y643400D03*
X247717Y633233D03*
X259300Y635900D03*
X266906Y775531D03*
X249025Y827374D03*
X255697D03*
X261624D03*
X261811Y878276D03*
X249212D03*
X239764D03*
X255511D03*
X267669Y5500D03*
X271000Y184500D03*
X269849Y308414D03*
X269270Y315759D03*
X297729Y362571D03*
X284200Y465000D03*
X286181Y498546D03*
X291500Y497700D03*
X269000Y504962D03*
X275286Y504392D03*
X280749Y512744D03*
X300835Y578165D03*
Y583165D03*
X301000Y588665D03*
X288835Y593165D03*
X276300Y617350D03*
X281700Y634900D03*
X281100Y651700D03*
X285500Y704900D03*
X294000Y716000D03*
X278406Y716531D03*
X274406Y716598D03*
X270000Y732650D03*
X283161Y730092D03*
X281500Y748500D03*
X282378Y775431D03*
X298500Y752000D03*
X272116Y755592D03*
X298400Y775700D03*
X268296Y827374D03*
X280894D03*
X274222D03*
X286800Y863300D03*
X280800Y863500D03*
X268110Y878276D03*
X280708D03*
X287008D03*
X274410D03*
X329500Y192500D03*
X328000Y197400D03*
X334500Y197500D03*
Y192500D03*
X307300Y221702D03*
X307834Y237966D03*
X328842Y300042D03*
X316420Y331830D03*
X302749Y332651D03*
X326041Y329282D03*
X313875Y364201D03*
X310475Y364193D03*
X316315Y369889D03*
X316205Y376006D03*
X306612Y460177D03*
X307400Y467600D03*
X303440Y475360D03*
X303500Y491000D03*
X322700Y536500D03*
X311406Y535944D03*
X322100Y638500D03*
X322178Y729178D03*
X310016Y729793D03*
X312500Y716500D03*
X313452Y753856D03*
X330000Y754000D03*
X312017Y827374D03*
X318689D03*
X324616D03*
X331288D03*
X306500Y868700D03*
X312000Y868600D03*
X324803Y878276D03*
X331102D03*
X318503D03*
X312500Y878200D03*
X344000Y197500D03*
X339500D03*
X344000Y192500D03*
X339500D03*
X344958Y300740D03*
X344955Y305843D03*
X359500Y448800D03*
X342300Y511600D03*
X350000Y537600D03*
X347100Y605300D03*
X357600Y638300D03*
X366792Y734171D03*
X364275Y723033D03*
X359500Y727335D03*
X342900Y727200D03*
X349813Y827374D03*
X356485D03*
X362411D03*
X343886D03*
X337214D03*
X362599Y878276D03*
X356299D03*
X350000D03*
X343700D03*
X337402D03*
X387669Y5500D03*
X401300Y159800D03*
X401200Y150200D03*
X395100Y449100D03*
X380300Y508700D03*
X401000Y575500D03*
X372000Y579300D03*
X388900Y550400D03*
X386500Y607900D03*
X374275Y722919D03*
X369083Y827374D03*
X384459D03*
X391131D03*
X397057D03*
X378346Y878276D03*
X390944D03*
X397244D03*
X384646D03*
X370500Y878200D03*
X407669Y5500D03*
X427669D03*
X406500Y141700D03*
Y146900D03*
X404170Y326708D03*
X403900Y315492D03*
X416100Y470800D03*
X418900Y529300D03*
X410300Y637500D03*
X416328Y827374D03*
X428926D03*
X422254D03*
X403729D03*
X409656D03*
X416141Y878276D03*
X431889D03*
X422441D03*
X403543D03*
X409843D03*
X447669Y5500D03*
X467669D03*
X461900Y62300D03*
X452600Y114254D03*
X454871Y122291D03*
X457400Y138900D03*
X452500Y153300D03*
X455800Y208300D03*
X461389Y318510D03*
X459200Y369300D03*
X462700D03*
X466700Y388800D03*
X448200Y531400D03*
X443000Y596500D03*
X456335Y835051D03*
X444500Y864450D03*
X438189Y878276D03*
X489261Y-14185D03*
X470200Y62300D03*
X478400D03*
X479700Y90100D03*
X491466Y126683D03*
X494800Y162900D03*
X493186Y272414D03*
X501867Y295490D03*
X486700Y363800D03*
X470200D03*
X490200Y388800D03*
X491860Y382140D03*
X472600Y477700D03*
X487400Y492100D03*
X500800Y567200D03*
X487906Y768598D03*
X491906Y768531D03*
X496061Y781678D03*
X494582Y800500D03*
X483500Y784650D03*
X485300Y808250D03*
X496335Y835051D03*
X480406Y827531D03*
X495878Y827431D03*
X514309Y-315D03*
Y52087D03*
X530057Y67048D03*
Y52087D03*
X530400Y72400D03*
X524000Y43500D03*
X532500Y62900D03*
X536100Y56700D03*
X530057Y106457D03*
Y96969D03*
Y82008D03*
X531400Y102900D03*
X522700D03*
X528700Y91100D03*
X531200Y87900D03*
X535400Y87400D03*
X532900Y92400D03*
X532400Y78200D03*
X521465Y140964D03*
X513876D03*
X532110Y138400D03*
X525000D03*
X506006Y126183D03*
X515348Y163101D03*
X515354Y168998D03*
X505100Y164800D03*
X512600Y186500D03*
X534481Y243676D03*
X518277Y288680D03*
X532921Y298436D03*
X525347Y336979D03*
X512100Y319700D03*
X532499Y315591D03*
X533779Y336979D03*
X507809Y336341D03*
X522209Y333841D03*
X522409Y318441D03*
X518100Y453200D03*
X520500Y519400D03*
X527700Y587500D03*
X522500Y782031D03*
X535178Y781000D03*
X511800Y768300D03*
X528100Y767300D03*
X526274Y806000D03*
X511500Y803000D03*
X533800Y835500D03*
X527941Y864680D03*
X557616Y-315D03*
Y52087D03*
X538915Y67048D03*
X547773D03*
Y52087D03*
X538915D03*
X541200Y73400D03*
X541600Y62600D03*
X544500Y57400D03*
X546800Y46300D03*
X566700Y48700D03*
X570900Y56200D03*
X547773Y106457D03*
X538915Y96969D03*
X547773D03*
X538915Y82008D03*
X547773D03*
X537400Y91000D03*
X540100Y102900D03*
X541700Y92300D03*
X544600Y87300D03*
X538800Y76900D03*
X546800Y76200D03*
X566100Y103100D03*
X543000Y76300D03*
X539031Y136200D03*
X547400Y136170D03*
X560633Y127988D03*
X552800Y140800D03*
X543900Y154800D03*
X550300D03*
X554149Y200229D03*
X541446Y222562D03*
X565063Y256608D03*
Y247608D03*
Y252108D03*
X560318Y267199D03*
Y272199D03*
X560418Y278299D03*
Y283799D03*
Y289299D03*
X560318Y295699D03*
X539450Y322166D03*
X539507Y330787D03*
X554400Y335900D03*
X560531Y358080D03*
X564100Y358100D03*
X556500Y358000D03*
X561781Y346281D03*
X550000Y381000D03*
X542500Y806000D03*
X550186Y827374D03*
X543514D03*
X568711D03*
X556113D03*
X562785D03*
X538000Y878200D03*
X550000Y878276D03*
X562598D03*
X568898D03*
X556300D03*
X544000Y878200D03*
X600923Y-315D03*
Y52087D03*
X573364D03*
X582222D03*
X591080D03*
X573364Y67048D03*
X582222D03*
X591080D03*
X590000Y46200D03*
X579900Y55800D03*
X588000Y57200D03*
X584600Y63200D03*
X575800Y63100D03*
X588000Y72200D03*
X579000Y72300D03*
X573800Y72400D03*
X591080Y106457D03*
X573364D03*
X582222Y82008D03*
X591080D03*
X573364D03*
Y96969D03*
X582222D03*
X591080D03*
X576800Y91600D03*
X584600Y78200D03*
X575500Y78500D03*
X588000Y87100D03*
X579000Y87200D03*
X584500Y93200D03*
X580700Y90900D03*
X572500Y91200D03*
X576300Y103300D03*
X585100D03*
X580800Y76000D03*
X574100Y87800D03*
X579200Y140400D03*
X583640Y140636D03*
X598240Y137800D03*
X572990Y140501D03*
X588955Y140600D03*
X591377Y125797D03*
X597846Y125623D03*
X593000Y152800D03*
X598300Y152850D03*
X597763Y242608D03*
X602763Y240858D03*
X597763Y231608D03*
Y235108D03*
Y239108D03*
X602763Y236608D03*
Y232108D03*
X587100Y234800D03*
X597763Y246108D03*
Y250108D03*
X602763Y245108D03*
Y249608D03*
X605063Y257608D03*
X604170Y337900D03*
X599100Y348700D03*
X597500Y352050D03*
X589500Y361000D03*
X581700Y360700D03*
X573900Y360600D03*
X603500Y371200D03*
X576800Y369200D03*
X584500Y462500D03*
X600400Y538000D03*
X586900Y713200D03*
X593908Y827374D03*
X600580D03*
X587981D03*
X581309D03*
X575383D03*
X594095Y878276D03*
X600393D03*
X587795D03*
X575197D03*
X581497D03*
X616671Y52087D03*
X625529D03*
X634388D03*
X616671Y67048D03*
X625529D03*
X634388D03*
X631100Y72300D03*
X622100Y72400D03*
X628200Y62600D03*
X619200Y62800D03*
X614300Y55800D03*
X620838Y58628D03*
X634100Y46800D03*
X631300Y57100D03*
X616800Y72200D03*
X624700Y61400D03*
X634388Y106457D03*
X616671D03*
X625529Y82008D03*
X634388D03*
X616671D03*
Y96969D03*
X625529D03*
X634388D03*
X611100Y103300D03*
X619600D03*
X628300D03*
X615800Y91200D03*
X624400Y91100D03*
X628000Y93000D03*
X618300Y88000D03*
X628100Y77700D03*
X619400Y77500D03*
X631200Y87200D03*
X624000Y76000D03*
X621900Y87600D03*
X619700Y92100D03*
X629393Y140451D03*
X631940Y137800D03*
X607520Y137780D03*
X605924Y126398D03*
X633900Y149600D03*
X607763Y242608D03*
Y231608D03*
Y235108D03*
Y239108D03*
X619363Y225108D03*
X623363D03*
X611563Y278108D03*
X607763Y246108D03*
Y250108D03*
X607563Y265608D03*
X607463Y270608D03*
X607563Y261108D03*
X609063Y255608D03*
X607563Y276108D03*
Y282108D03*
Y287608D03*
Y293608D03*
X607519Y299497D03*
X611563Y290108D03*
Y284608D03*
X635350Y320850D03*
X606322Y351522D03*
X633000Y356600D03*
Y360500D03*
Y353000D03*
X636500Y356500D03*
X629500D03*
Y371000D03*
X626458Y372521D03*
X616706Y349718D03*
X618680Y346780D03*
X621300Y366900D03*
X609500Y360717D03*
X623000Y382500D03*
X617000D03*
X627600Y685000D03*
X608000Y700800D03*
X613178Y827374D03*
X606506D03*
X638375D03*
X631703D03*
X619105D03*
X625777D03*
X606693Y878276D03*
X619292D03*
X612992D03*
X625590D03*
X631890D03*
X644230Y-315D03*
Y52087D03*
X659978D03*
X668836D03*
X659978Y67048D03*
X668836D03*
X653300Y48600D03*
X665400Y72500D03*
X661100Y73000D03*
X662300Y63300D03*
X656700Y57400D03*
X665696Y57027D03*
X671100Y63400D03*
X659978Y106457D03*
X668836Y82008D03*
X659978D03*
Y96969D03*
X668836D03*
X656400Y102600D03*
X665100Y102700D03*
X660600Y93300D03*
X669400Y93200D03*
X659700Y86400D03*
X662400Y78100D03*
X667500Y76000D03*
X664000Y91100D03*
X671300Y78100D03*
X641159Y137800D03*
X643160Y149600D03*
X666593Y226677D03*
X662593Y223677D03*
X658093D03*
X671124Y210770D03*
X655500Y213500D03*
X670063Y274708D03*
X669633Y259148D03*
X672100Y299800D03*
X640532Y318099D03*
X643932Y318104D03*
X639500Y342500D03*
X652254Y336353D03*
X662897Y346873D03*
X663140Y353982D03*
X646884Y355616D03*
X639500Y371000D03*
X653000Y380500D03*
X644100Y488700D03*
X639500Y678500D03*
X657000Y714500D03*
X668500Y700000D03*
X648900Y782500D03*
X666348Y827374D03*
X653750D03*
X660422D03*
X653500Y819100D03*
X647838Y872000D03*
X660236Y878276D03*
X666536D03*
X654000Y878200D03*
X642200Y877900D03*
X687537Y-315D03*
Y52087D03*
X677695D03*
Y67048D03*
X674600Y72200D03*
X676800Y46300D03*
X677695Y106457D03*
Y82008D03*
Y96969D03*
X674300Y102400D03*
X678300Y93100D03*
X674800Y86800D03*
X678063Y238108D03*
X673063D03*
X672927Y219677D03*
X677927D03*
X686063Y230108D03*
X696800Y237900D03*
X682763Y238008D03*
X686063Y224608D03*
X687253Y237878D03*
X691753D03*
X698300Y226500D03*
X693800D03*
X685115Y210677D03*
X689623Y269648D03*
X694963Y269608D03*
X689723Y274748D03*
X694223D03*
X679723D03*
X684223D03*
X690233Y255748D03*
X695000Y255800D03*
X690133Y260348D03*
X694633D03*
X680133Y259148D03*
X684633D03*
X674563Y274708D03*
X674133Y259148D03*
X695963Y302308D03*
Y297808D03*
Y293308D03*
X690663Y287608D03*
Y292108D03*
X689500Y344000D03*
X704500Y343000D03*
X676700Y378800D03*
X687000Y378700D03*
X678500Y684000D03*
X673020Y827374D03*
X698217D03*
X691545D03*
X678947D03*
X685619D03*
X698100Y821600D03*
X703900Y866100D03*
X697700D03*
X704331Y878276D03*
X698031D03*
X691733D03*
X685433D03*
X679134D03*
X672834D03*
X736308Y-7483D03*
X711919Y6754D03*
X729555Y33100D03*
X709120Y35980D03*
X719555Y33100D03*
X735186Y20714D03*
X727265Y52588D03*
X726646Y42651D03*
X721690Y53340D03*
X723501Y82680D03*
X723481Y76780D03*
X723610Y106430D03*
X723569Y100969D03*
X723659Y97292D03*
X723429Y91683D03*
X735157Y97005D03*
X735326Y102660D03*
X723438Y112700D03*
X723638Y118353D03*
X725300Y228700D03*
X730300D03*
X711300D03*
X716300D03*
X738800Y272000D03*
Y265500D03*
Y258000D03*
Y251500D03*
X706800Y272500D03*
Y265500D03*
Y258000D03*
Y252000D03*
X715300Y272000D03*
Y265500D03*
Y258000D03*
Y251500D03*
X724300Y272000D03*
Y265500D03*
Y258000D03*
Y251500D03*
X732300Y272000D03*
Y265500D03*
Y258000D03*
Y251500D03*
X713000Y310000D03*
X724400Y626500D03*
X735640Y827374D03*
X723041D03*
X729713D03*
X729527Y878276D03*
X735827D03*
X723000Y878200D03*
X752763Y38638D03*
X771600Y24200D03*
X747000Y44300D03*
X762250Y44650D03*
X753500Y96600D03*
X762400Y127600D03*
X753500Y110900D03*
X769400Y111900D03*
X749337Y212192D03*
X746037Y213992D03*
X746237Y210392D03*
X743500Y362000D03*
X753000Y359000D03*
X743000Y598000D03*
X773435Y827374D03*
X754910D03*
X748238D03*
X742312D03*
X760837D03*
X767509D03*
X754724Y878276D03*
X761024D03*
X767323D03*
X742126D03*
X748426D03*
X788550Y29350D03*
X781500Y85100D03*
X797800Y104500D03*
X776538Y107162D03*
X773900Y138300D03*
X780800Y545900D03*
X786033Y827374D03*
X780107D03*
X792705D03*
X798632D03*
X805304D03*
X779921Y878276D03*
X786221D03*
X792519D03*
X798819D03*
X805118D03*
X773623D03*
X830773Y9000D03*
X834227D03*
X831592Y34411D03*
X832401Y46472D03*
X831125Y67775D03*
X833900Y467000D03*
X812500Y499400D03*
X836427Y827374D03*
X817902D03*
X811230D03*
X836615Y878276D03*
X830315D03*
X811418D03*
X820000Y878200D03*
X867600Y2500D03*
X855489Y9811D03*
X859300Y9900D03*
X874300Y18875D03*
X858500Y40000D03*
Y32000D03*
X869447Y31024D03*
X843500Y9150D03*
X851870Y52160D03*
X847337Y46563D03*
X851300Y45748D03*
X844900Y85100D03*
X874410Y127953D03*
X851500Y705500D03*
X852500Y718000D03*
X847500Y717500D03*
X857406Y745598D03*
X861406Y745531D03*
X855500Y775500D03*
X844150Y762150D03*
X858695Y759900D03*
X871000Y776500D03*
X849906Y804531D03*
X865378Y804431D03*
X851890Y789270D03*
X870900Y812104D03*
X855697Y827374D03*
X849025D03*
X843099D03*
X861823Y853696D03*
X849213Y878276D03*
X842913D03*
X856000Y878200D03*
X904262Y14894D03*
X880883Y30583D03*
X892745Y9681D03*
X890000Y97800D03*
X897000Y96700D03*
X905906Y127953D03*
X901969Y124016D03*
X894095D03*
X890158Y127953D03*
X901969D03*
X898032D03*
X894095D03*
X882284Y139764D03*
X886221Y135827D03*
X882284Y131890D03*
X886221Y124016D03*
X878347D03*
X886221Y127953D03*
X882284D03*
X878347D03*
X882284Y155512D03*
X886221Y151575D03*
X882284Y147638D03*
X886221Y143701D03*
X898032Y194881D03*
Y198818D03*
Y202755D03*
X894095D03*
X898032Y179134D03*
Y183071D03*
Y190944D03*
Y238188D03*
X894095D03*
X898032Y234251D03*
Y230314D03*
X905906Y238188D03*
X901969D03*
X898032Y226377D03*
Y222440D03*
Y218503D03*
Y214566D03*
Y210629D03*
X902500Y370000D03*
X897000Y370500D03*
X907500Y368000D03*
X900999Y748550D03*
X885400Y743600D03*
X900824Y781531D03*
X895278Y758885D03*
X874887Y759253D03*
X884671Y775500D03*
X885167Y816593D03*
X884412Y835051D03*
X927250Y31450D03*
X913780Y127953D03*
Y139764D03*
X921654Y127953D03*
X929528D03*
X937402Y175197D03*
X941339Y171260D03*
X937402Y167323D03*
X941339Y163386D03*
X929528Y175197D03*
X933465Y171260D03*
X929528Y167323D03*
X933465Y163386D03*
X925591Y171260D03*
X921654Y175197D03*
X925591Y163386D03*
X921654Y167323D03*
X917717Y163386D03*
Y171260D03*
X921654Y159449D03*
X925591Y151575D03*
X913780Y183071D03*
X921654Y194881D03*
X917717Y198818D03*
X937402Y194881D03*
X933465Y198818D03*
X929528Y202755D03*
X925591Y206692D03*
X929528Y194881D03*
X925591Y198818D03*
X921654Y202755D03*
X917717Y206692D03*
X933465D03*
X937402Y202755D03*
X941339Y198818D03*
Y206692D03*
X925591Y190944D03*
X933465Y179134D03*
X929528Y183071D03*
X925591Y179134D03*
X921654Y183071D03*
X941339Y190944D03*
X933465D03*
X937402Y183071D03*
X941339Y179134D03*
X917717Y190944D03*
X921654Y238188D03*
X917717D03*
X913780D03*
X909843D03*
X913780Y214566D03*
X941339Y226377D03*
X937402Y222440D03*
X933465Y226377D03*
X929528Y222440D03*
X925591Y226377D03*
X929528Y230314D03*
X937402D03*
X941339Y234251D03*
X937402Y238188D03*
X933465Y234251D03*
X929528Y238188D03*
X925591Y234251D03*
X921654Y210629D03*
X925591Y214566D03*
X929528Y210629D03*
X941339Y214566D03*
X933465D03*
X937402Y210629D03*
X909000Y353600D03*
X908700Y347300D03*
X938898Y640169D03*
X916319Y678588D03*
Y658588D03*
Y698588D03*
Y738588D03*
Y718588D03*
Y778588D03*
Y758588D03*
Y798588D03*
Y818588D03*
X969100Y14600D03*
X976066Y26581D03*
X971466Y26681D03*
X942500Y30100D03*
X967180Y66705D03*
X949212Y167323D03*
X964960D03*
X968897Y163386D03*
X957086Y175197D03*
X961023Y171260D03*
X953149D03*
X949212Y175197D03*
X961023Y163386D03*
X957086Y167323D03*
X972834D03*
X968897Y171260D03*
X964960Y175197D03*
X972834D03*
X949212Y194881D03*
X968897Y198818D03*
X964960Y202755D03*
X961023Y206692D03*
X972834Y194881D03*
X953149Y206692D03*
X964960Y194881D03*
X961023Y198818D03*
X957086Y202755D03*
X949212D03*
X953149Y198818D03*
X957086Y194881D03*
X972834Y202755D03*
X968897Y206692D03*
X949212Y183071D03*
X953149Y179134D03*
X961023D03*
X957086Y183071D03*
X953149Y190944D03*
X968897D03*
X972834Y183071D03*
X961023Y190944D03*
X964960Y183071D03*
X968897Y179134D03*
Y226377D03*
Y234251D03*
X953149Y226377D03*
X949212Y222440D03*
Y230314D03*
X964960Y222440D03*
X961023Y226377D03*
X957086Y222440D03*
X964960Y230314D03*
X957086D03*
X953149Y234251D03*
X949212Y238188D03*
X964960D03*
X961023Y234251D03*
X957086Y238188D03*
X953149Y214566D03*
X957086Y210629D03*
X949212D03*
X972834D03*
X968897Y214566D03*
X961023D03*
X964960Y210629D03*
X957800Y570300D03*
X958898Y640169D03*
X976500Y4500D03*
X985880Y41686D03*
X980100Y14500D03*
X1000985Y29307D03*
X1007921Y39585D03*
X980566Y26581D03*
X985315Y14425D03*
X997385Y29307D03*
X985880Y46086D03*
Y50586D03*
X992396Y45073D03*
X976771Y163386D03*
Y171260D03*
Y206692D03*
Y198818D03*
Y190944D03*
X1006100Y528700D03*
X977500Y550000D03*
X978898Y640169D03*
X994248Y665818D03*
Y685818D03*
Y705818D03*
Y745818D03*
Y725818D03*
Y765818D03*
Y805818D03*
Y785818D03*
X1025700Y7600D03*
X1024330Y34379D03*
X1040218Y32140D03*
X1010229Y19022D03*
X1022300Y13900D03*
X1035783Y51473D03*
X1017863Y45056D03*
X1028500Y257500D03*
X1012600Y476700D03*
X1022600Y542100D03*
X1017800Y572700D03*
X1043300Y631300D03*
X1041500Y682000D03*
X1041900Y658100D03*
X1039577Y827374D03*
X1024004Y855893D03*
X1033464Y878276D03*
X1039764D03*
X1069261Y-14185D03*
X1049261D03*
X1061253Y17487D03*
X1062470Y31823D03*
X1062433Y37099D03*
X1056049Y18396D03*
X1061153Y27488D03*
X1046200Y24500D03*
X1054835Y40386D03*
X1072140Y16447D03*
X1047429Y15229D03*
X1054210Y53370D03*
X1054090Y58470D03*
X1068315Y56120D03*
X1068390Y61611D03*
X1074103Y44988D03*
X1047000Y644000D03*
X1045000Y617500D03*
X1067000Y711000D03*
X1062500Y738000D03*
X1058500Y758000D03*
X1058847Y827374D03*
X1052175D03*
X1046249D03*
X1064774D03*
X1071446D03*
X1046063Y878276D03*
X1071260D03*
X1064961D03*
X1058661D03*
X1052363D03*
X1089261Y-14185D03*
X1103424Y67690D03*
X1110664Y78483D03*
X1103253Y76910D03*
X1079500Y631000D03*
X1080000Y650500D03*
X1081000Y670000D03*
X1084044Y827374D03*
X1077372D03*
X1102569D03*
X1109241D03*
X1089970D03*
X1096642D03*
X1090158Y878276D03*
X1083858D03*
X1077560D03*
X1096456D03*
X1102756D03*
X1109055D03*
X1116671Y-315D03*
Y52087D03*
X1132419Y67048D03*
X1141277D03*
Y52087D03*
X1132419D03*
X1127300Y46300D03*
X1122800Y55100D03*
X1132100Y56300D03*
X1131900Y70700D03*
X1140900Y71100D03*
X1141900Y63300D03*
X1132419Y106457D03*
Y96969D03*
X1141277D03*
X1132419Y82008D03*
X1141277D03*
X1142418Y78638D03*
X1131800Y85600D03*
X1141200Y86800D03*
X1126400Y92200D03*
X1143500Y93300D03*
X1123000Y99200D03*
X1131880Y100377D03*
X1134800Y93300D03*
X1116933Y85243D03*
X1140364Y827374D03*
X1121839D03*
X1115167D03*
X1127766D03*
X1134438D03*
X1140552Y878276D03*
X1115355D03*
X1127953D03*
X1134252D03*
X1121653D03*
X1159978Y-315D03*
Y52087D03*
X1175726D03*
Y67048D03*
X1150135D03*
Y52087D03*
X1175300Y71100D03*
X1175100Y55700D03*
X1166500Y56200D03*
X1171700Y45900D03*
X1149100Y46300D03*
X1150700Y63300D03*
X1175726Y106457D03*
X1150135D03*
X1175726Y82008D03*
Y96969D03*
X1150135D03*
Y82008D03*
X1148900Y75900D03*
X1168400Y103000D03*
X1177000Y102800D03*
X1176200Y92900D03*
X1178100Y78000D03*
X1175200Y85900D03*
X1151492Y78668D03*
X1164857Y138505D03*
X1175851Y142410D03*
X1177600Y241200D03*
X1173400D03*
X1166400Y234300D03*
X1170600D03*
X1175700D03*
X1177200Y248200D03*
X1173000D03*
X1177300Y254400D03*
X1173100D03*
X1176300Y261500D03*
X1171200D03*
X1167000D03*
X1161700Y818500D03*
X1159634Y827374D03*
X1152962D03*
X1147036D03*
X1175010D03*
X1174900Y818300D03*
X1159448Y878276D03*
X1153150D03*
X1173623Y878200D03*
X1146850Y878276D03*
X1165748D03*
X1203285Y-315D03*
Y52087D03*
X1184584D03*
X1193442D03*
X1184584Y67048D03*
X1193442D03*
X1185200Y72600D03*
X1210511Y52300D03*
X1193555Y61875D03*
X1183884Y61598D03*
X1188200Y61600D03*
X1192300Y46100D03*
X1184100Y56100D03*
X1193442Y106457D03*
X1184584Y82008D03*
X1193442D03*
X1184584Y96969D03*
X1193442D03*
X1193900Y78000D03*
X1211500Y102900D03*
X1194000Y93200D03*
X1185800Y102900D03*
X1185100Y93000D03*
X1187100Y77900D03*
X1184800Y87200D03*
X1202410Y142850D03*
X1193845Y137855D03*
X1184629Y137740D03*
X1185070Y142384D03*
X1210391Y156730D03*
X1200391Y156779D03*
X1193192Y142970D03*
X1203100Y241100D03*
X1198900D03*
X1207900D03*
X1182400Y241200D03*
X1197900Y234300D03*
X1207400D03*
X1203200D03*
X1179900D03*
X1188900D03*
X1184700D03*
X1193700D03*
X1182000Y248200D03*
X1202600Y254100D03*
X1198400D03*
X1207400D03*
X1202500Y247500D03*
X1198300D03*
X1207300D03*
X1182100Y254400D03*
X1203800Y261500D03*
X1208000D03*
X1194300D03*
X1198500D03*
X1185300D03*
X1189500D03*
X1180500D03*
X1205500Y334400D03*
X1194280Y827374D03*
X1187608D03*
X1181682D03*
X1200735Y864273D03*
X1194063D03*
X1200394Y878276D03*
X1194094D03*
X1187796D03*
X1181496D03*
X1246592Y-315D03*
Y52087D03*
X1219033D03*
X1227891D03*
X1236750D03*
X1219033Y67048D03*
X1227891D03*
X1236750D03*
X1231400Y58300D03*
X1215400Y57600D03*
X1216300Y72900D03*
X1235800Y46400D03*
X1228000Y57000D03*
X1218600Y56000D03*
X1214700Y46000D03*
X1221200Y63400D03*
X1230300Y63200D03*
X1228900Y72900D03*
X1236750Y106457D03*
X1219033D03*
X1227891Y82008D03*
X1236750D03*
X1219033D03*
Y96969D03*
X1227891D03*
X1236750D03*
X1230000Y78800D03*
X1221300Y78400D03*
X1219200Y87000D03*
X1229100Y87900D03*
X1232500Y90900D03*
X1229900Y103100D03*
X1228300Y93100D03*
X1219500Y93300D03*
X1220100Y102700D03*
X1219138Y137928D03*
X1227999Y142465D03*
X1236692Y137720D03*
X1237219Y142420D03*
X1228359Y137960D03*
X1229000Y210500D03*
X1242500Y209000D03*
X1232000Y194500D03*
X1237000D03*
X1226500Y201500D03*
Y194500D03*
X1244500D03*
X1212900Y234300D03*
X1233900Y240700D03*
X1239900D03*
X1244900D03*
X1228900D03*
X1228500Y235000D03*
X1234000D03*
X1240000D03*
X1245000D03*
X1214000Y261500D03*
X1233800Y246600D03*
X1239800D03*
X1244800D03*
X1228800D03*
X1229000Y252000D03*
X1245000D03*
X1240000D03*
X1234000D03*
X1226000Y261300D03*
X1227000Y279000D03*
X1242000D03*
X1232000Y292000D03*
X1237000D03*
X1227000Y285500D03*
X1244500Y292000D03*
X1242000Y343000D03*
X1235400Y364400D03*
X1213400Y355400D03*
X1214100Y469800D03*
X1237800Y524500D03*
X1232300Y568900D03*
X1238375Y827374D03*
X1231703D03*
X1219105D03*
X1225777D03*
X1244302D03*
X1217717Y878076D03*
X1225590Y878276D03*
X1231890D03*
X1244489D03*
X1238189D03*
X1262340Y52087D03*
X1271198D03*
X1280057D03*
X1262340Y67048D03*
X1271198D03*
X1280057D03*
X1261900Y71039D03*
X1265500Y61900D03*
X1272200Y72900D03*
X1275200Y61200D03*
X1269900Y61100D03*
X1279100Y46300D03*
X1272200Y57900D03*
X1258400Y45900D03*
X1254500Y51100D03*
X1280057Y106457D03*
X1262340D03*
X1271198Y82008D03*
X1280057D03*
X1262340D03*
Y96969D03*
X1271198D03*
X1280057D03*
X1271300Y77100D03*
X1273200Y103200D03*
X1256000Y103300D03*
X1263200Y102700D03*
X1270300Y91100D03*
X1262800Y93100D03*
X1254200Y96300D03*
X1275500Y91000D03*
X1272700Y88000D03*
X1265200Y77400D03*
X1261900Y86000D03*
X1275800Y75900D03*
X1252768Y141181D03*
X1278160Y140547D03*
X1257899Y142881D03*
X1245910Y137810D03*
X1273068Y140514D03*
X1262880Y142909D03*
X1247500Y209000D03*
X1252500Y194500D03*
X1263000Y210307D03*
X1257500Y194500D03*
X1263000Y202000D03*
X1262500Y194500D03*
X1255900Y240700D03*
X1249900D03*
X1262500Y235000D03*
X1250000D03*
X1256000D03*
X1255800Y246600D03*
X1249800D03*
X1275500Y264500D03*
X1262000Y252000D03*
X1256000D03*
X1250000D03*
X1247000Y279000D03*
X1262500Y279500D03*
X1252000Y292000D03*
X1257000D03*
X1262500Y286000D03*
X1258500Y335500D03*
X1266500D03*
X1273500Y397000D03*
X1257500D03*
X1254000D03*
X1259200Y471800D03*
X1259000Y680000D03*
X1265000Y672000D03*
X1253500D03*
X1278000Y689000D03*
X1263572Y827374D03*
X1269498D03*
X1276170D03*
X1256900D03*
X1250974D03*
X1263386Y878276D03*
X1275984D03*
X1257087D03*
X1269686D03*
X1250787D03*
X1289899Y-315D03*
Y52087D03*
X1291660Y140257D03*
X1297360Y140172D03*
X1301749Y125479D03*
X1282189Y144361D03*
X1287637Y144386D03*
X1297668Y155524D03*
X1290870Y186285D03*
X1311181Y186548D03*
X1297500Y351800D03*
X1291600Y495200D03*
X1296400Y542400D03*
X1294700Y593400D03*
X1302128Y674067D03*
X1306128Y674000D03*
X1285000Y694000D03*
X1280500Y706000D03*
X1310376Y687205D03*
X1301728Y711200D03*
X1310100Y732900D03*
X1294628Y733000D03*
X1304800Y811900D03*
X1288768Y827374D03*
X1282096D03*
X1307294D03*
X1301800Y878100D03*
X1294268Y872169D03*
X1288582Y878276D03*
X1282284D03*
X1307481D03*
X1324845Y130527D03*
X1325429Y148270D03*
X1327782Y192579D03*
Y200579D03*
Y207579D03*
X1328411Y237679D03*
X1327782Y215579D03*
Y221579D03*
X1327841Y228639D03*
X1332683Y240409D03*
X1328356Y242091D03*
X1328317Y246291D03*
X1332683Y244609D03*
Y248809D03*
X1337000Y263250D03*
X1332000Y261500D03*
Y265000D03*
Y268500D03*
Y272500D03*
Y257500D03*
Y254000D03*
X1342000D03*
Y257500D03*
Y261500D03*
Y265000D03*
Y268500D03*
Y272500D03*
X1337000Y267500D03*
Y272000D03*
Y259000D03*
Y254500D03*
X1322250Y282250D03*
X1345850Y676750D03*
X1326250Y669550D03*
X1333500Y709500D03*
X1323076Y686999D03*
X1338200Y689800D03*
X1315546Y709500D03*
X1341400Y686900D03*
X1326661Y740700D03*
X1345088Y827374D03*
X1332490D03*
X1339162D03*
X1326564D03*
X1319892D03*
X1313966D03*
X1320079Y878276D03*
X1345276D03*
X1332678D03*
X1338976D03*
X1326378D03*
X1313779D03*
X1368028Y175745D03*
X1366672Y210312D03*
X1375196Y217203D03*
X1367042Y223895D03*
X1375359Y230110D03*
X1372000Y240500D03*
X1368300Y267800D03*
X1358662Y275485D03*
X1372000Y245300D03*
Y249500D03*
X1369700Y424600D03*
X1366000Y472900D03*
X1363900Y537600D03*
X1361800Y596800D03*
X1358700Y655700D03*
X1348500Y713000D03*
X1377000Y725000D03*
X1378000Y806900D03*
X1369925Y835051D03*
X1351760Y827374D03*
X1357886Y864246D03*
X1352200Y878400D03*
X1394500Y139626D03*
Y119626D03*
Y159626D03*
Y199626D03*
Y179626D03*
X1381568Y180579D03*
X1394500Y239626D03*
Y219626D03*
Y259626D03*
Y299626D03*
Y279626D03*
Y339626D03*
Y319626D03*
Y359626D03*
Y399626D03*
Y379626D03*
Y439626D03*
Y419626D03*
Y479626D03*
Y459626D03*
Y499626D03*
Y539626D03*
Y519626D03*
Y579626D03*
Y559626D03*
Y599626D03*
Y639626D03*
Y619626D03*
Y679626D03*
Y659626D03*
Y699626D03*
Y739626D03*
Y719626D03*
Y759626D03*
Y779626D03*
Y799626D03*
Y819626D03*
X1389925Y835051D03*
G54D33*
X501742Y215594D03*
G54D10*
X700Y19100D03*
X16200Y120100D03*
X27200Y821800D03*
X33800Y872600D03*
X1384200Y122800D03*
X1373200Y823500D03*
X1415100Y-36700D03*
X1389800Y879000D03*
G54D16*
X39370Y801181D03*
X1360630Y135826D03*
Y801181D03*
G54D19*
X54378Y237402D03*
G54D22*
X122165Y142874D03*
X173897D03*
G54D17*
X42587Y151614D03*
X80579D03*
G54D30*
X336417Y21260D03*
X293110Y55906D03*
X336417Y90551D03*
X789850Y236220D03*
Y283464D03*
X1376968Y21260D03*
X1333661Y55906D03*
X1376968Y90551D03*
G54D15*
X25050Y716900D03*
X71500Y297900D03*
X77100Y303800D03*
X65400D03*
X65500Y291900D03*
X77500D03*
X191000Y246500D03*
X534481Y286876D03*
G54D34*
X535962Y37520D03*
X579269D03*
X622577D03*
X665884D03*
X1138324D03*
X1181631D03*
X1224939D03*
X1268246D03*
G54D27*
X161811Y153543D03*
%LPC*%
G75*
G54D37*
G01X127746Y-260199D02*
X95746D01*
G01X127746Y-276199D02*
Y-356199D01*
G01D02*
X1310146D01*
G01X127746Y-311699D02*
X1310146D01*
G01X123746Y-260199D02*
G02I-12000J0D01*
G01X118596D02*
G02I-6850J0D01*
G01X111746Y-276199D02*
Y-244199D01*
G01X127746Y-276199D02*
X1310146D01*
G01X522646D02*
Y-356199D01*
G01X660146Y-276199D02*
Y-356199D01*
G01X775146Y-276199D02*
Y-356199D01*
G01X942646Y-276199D02*
Y-356199D01*
G01X1112646Y-276199D02*
Y-356199D01*
G01X1310146Y-276199D02*
Y-356199D01*
G01X1342146Y-260199D02*
X1310146D01*
G01X1338146D02*
G02I-12000J0D01*
G01X1332996D02*
G02I-6850J0D01*
G01X1326146Y-276199D02*
Y-244199D01*
G54D38*
G01X145579Y-328699D02*
Y-346199D01*
X154313D01*
G01X167446Y-334533D02*
Y-346199D01*
G01Y-329866D02*
X167009Y-329574D01*
Y-328991D01*
X167446Y-328699D01*
X167883Y-328991D01*
Y-329574D01*
X167446Y-329866D01*
G01X181889Y-350574D02*
X183418Y-351741D01*
X185164Y-352032D01*
X186692Y-351741D01*
X188003Y-350283D01*
X188876Y-348241D01*
Y-334533D01*
G01Y-336866D02*
X188003Y-335699D01*
X186692Y-334824D01*
X185164Y-334533D01*
X183418Y-335116D01*
X182326Y-336282D01*
X181452Y-338324D01*
X181016Y-340366D01*
X181234Y-342116D01*
X182108Y-344158D01*
X183418Y-345616D01*
X185164Y-346199D01*
X186474Y-345907D01*
X188003Y-344741D01*
X188876Y-343575D01*
G01X198734Y-346199D02*
Y-328699D01*
G01Y-337157D02*
X199826Y-335699D01*
X200918Y-334824D01*
X202664Y-334533D01*
X203974Y-334824D01*
X205503Y-335991D01*
X206158Y-337741D01*
Y-346199D01*
G01X219946Y-328699D02*
Y-346199D01*
G01X216889Y-334533D02*
X223003D01*
G01X233734Y-346199D02*
Y-334533D01*
G01Y-337449D02*
X234608Y-335991D01*
X235918Y-334824D01*
X237664Y-334533D01*
X239192Y-334824D01*
X240503Y-335991D01*
X241158Y-338032D01*
Y-346199D01*
G01X254946Y-334533D02*
Y-346199D01*
G01Y-329866D02*
X254509Y-329574D01*
Y-328991D01*
X254946Y-328699D01*
X255383Y-328991D01*
Y-329574D01*
X254946Y-329866D01*
G01X268734Y-346199D02*
Y-334533D01*
G01Y-337449D02*
X269608Y-335991D01*
X270918Y-334824D01*
X272664Y-334533D01*
X274192Y-334824D01*
X275503Y-335991D01*
X276158Y-338032D01*
Y-346199D01*
G01X286889Y-350574D02*
X288418Y-351741D01*
X290164Y-352032D01*
X291692Y-351741D01*
X293003Y-350283D01*
X293876Y-348241D01*
Y-334533D01*
G01Y-336866D02*
X293003Y-335699D01*
X291692Y-334824D01*
X290164Y-334533D01*
X288418Y-335116D01*
X287326Y-336282D01*
X286452Y-338324D01*
X286016Y-340366D01*
X286234Y-342116D01*
X287108Y-344158D01*
X288418Y-345616D01*
X290164Y-346199D01*
X291474Y-345907D01*
X293003Y-344741D01*
X293876Y-343575D01*
G01X320579Y-346199D02*
Y-328699D01*
X325819D01*
X327566Y-329574D01*
X328876Y-331616D01*
X329313Y-333949D01*
X328876Y-336282D01*
X327784Y-338032D01*
X325819Y-338908D01*
X320579D01*
G01X346813Y-346199D02*
X338079D01*
Y-328699D01*
X346813D01*
G01X343319Y-337157D02*
X338079D01*
G01X361692Y-336866D02*
X362566Y-335991D01*
X363221Y-334533D01*
X363658Y-332490D01*
X363221Y-330741D01*
X362348Y-329574D01*
X360819Y-328699D01*
X354924D01*
Y-346199D01*
X362129D01*
X363658Y-345033D01*
X364531Y-343282D01*
X364968Y-341241D01*
X364531Y-339199D01*
X363221Y-337449D01*
X361692Y-336866D01*
X354924D01*
G01X390579Y-346199D02*
Y-328699D01*
X395819D01*
X397566Y-329574D01*
X398876Y-331616D01*
X399313Y-333949D01*
X398876Y-336282D01*
X397784Y-338032D01*
X395819Y-338908D01*
X390579D01*
G01X406769Y-346199D02*
Y-328699D01*
X412446Y-343282D01*
X418123Y-328699D01*
Y-346199D01*
G01X434749Y-330158D02*
X433439Y-329282D01*
X431911Y-328699D01*
X430164D01*
X428199Y-329574D01*
X426671Y-331032D01*
X425579Y-332783D01*
X424706Y-335699D01*
X424487Y-338324D01*
X424924Y-340949D01*
X425579Y-342699D01*
X426889Y-344449D01*
X428418Y-345616D01*
X429946Y-346199D01*
X431474D01*
X433003Y-345616D01*
X434313Y-344741D01*
X435405Y-343575D01*
G01X460579Y-346199D02*
Y-328699D01*
X465819D01*
X467566Y-329574D01*
X468876Y-331616D01*
X469313Y-333949D01*
X468876Y-336282D01*
X467784Y-338032D01*
X465819Y-338908D01*
X460579D01*
G01X476987Y-328699D02*
X482446Y-346199D01*
X487905Y-328699D01*
G01X499946D02*
Y-346199D01*
G01X494924Y-328699D02*
X504968D01*
G01X284269Y-301199D02*
Y-283699D01*
X289946Y-298282D01*
X295623Y-283699D01*
Y-301199D01*
G01X307446D02*
X306136Y-300907D01*
X304826Y-299741D01*
X303952Y-297699D01*
X303516Y-295366D01*
X303952Y-293032D01*
X304826Y-290991D01*
X306136Y-289824D01*
X307446Y-289533D01*
X308756Y-289824D01*
X310066Y-290991D01*
X310939Y-293032D01*
X311158Y-295366D01*
X310939Y-297699D01*
X310066Y-299741D01*
X308756Y-300907D01*
X307446Y-301199D01*
G01X328876Y-283699D02*
Y-301199D01*
G01Y-298575D02*
X328003Y-300033D01*
X326692Y-300907D01*
X325164Y-301199D01*
X323418Y-300616D01*
X322108Y-299158D01*
X321234Y-297408D01*
X321016Y-295366D01*
X321234Y-293324D01*
X322108Y-291574D01*
X323418Y-290116D01*
X325164Y-289533D01*
X326692Y-289824D01*
X327784Y-290408D01*
X328876Y-291574D01*
G01X339171Y-293324D02*
X346158D01*
X345503Y-291282D01*
X344411Y-290116D01*
X342883Y-289533D01*
X341354Y-289824D01*
X340044Y-290699D01*
X339171Y-292741D01*
X338734Y-294491D01*
Y-296241D01*
X339171Y-297991D01*
X340263Y-299741D01*
X341573Y-300907D01*
X343101Y-301199D01*
X344629Y-300616D01*
X346158Y-298866D01*
G01X359946Y-301199D02*
Y-283699D01*
G01X556346Y-346199D02*
Y-328699D01*
X553726Y-332199D01*
G01Y-346199D02*
X558966D01*
G01X569043Y-343575D02*
X570352Y-345033D01*
X571881Y-345907D01*
X573846Y-346199D01*
X575811Y-345616D01*
X577339Y-344449D01*
X578431Y-342408D01*
X578649Y-340074D01*
X578213Y-337741D01*
X577121Y-336282D01*
X575592Y-335116D01*
X574064Y-334824D01*
X572536Y-335116D01*
X570571Y-336282D01*
X571226Y-328699D01*
X577121D01*
G01X591346Y-346199D02*
Y-328699D01*
X588726Y-332199D01*
G01Y-346199D02*
X593966D01*
G01X608846Y-328699D02*
X607099Y-329282D01*
X605789Y-330741D01*
X604916Y-332490D01*
X604261Y-334824D01*
X604043Y-337449D01*
X604261Y-340074D01*
X604916Y-342408D01*
X605789Y-344158D01*
X607099Y-345616D01*
X608846Y-346199D01*
X610592Y-345616D01*
X611903Y-344158D01*
X612776Y-342408D01*
X613431Y-340074D01*
X613649Y-337449D01*
X613431Y-334824D01*
X612776Y-332490D01*
X611903Y-330741D01*
X610592Y-329282D01*
X608846Y-328699D01*
G01X621543Y-343575D02*
X622852Y-345033D01*
X624381Y-345907D01*
X626346Y-346199D01*
X628311Y-345616D01*
X629839Y-344449D01*
X630931Y-342408D01*
X631149Y-340074D01*
X630713Y-337741D01*
X629621Y-336282D01*
X628092Y-335116D01*
X626564Y-334824D01*
X625036Y-335116D01*
X623071Y-336282D01*
X623726Y-328699D01*
X629621D01*
G01X543229Y-301199D02*
Y-283699D01*
X548469D01*
X550216Y-284574D01*
X551526Y-286616D01*
X551963Y-288949D01*
X551526Y-291282D01*
X550434Y-293032D01*
X548469Y-293908D01*
X543229D01*
G01X569899Y-285158D02*
X568589Y-284282D01*
X567061Y-283699D01*
X565314D01*
X563349Y-284574D01*
X561821Y-286032D01*
X560729Y-287783D01*
X559856Y-290699D01*
X559637Y-293324D01*
X560074Y-295949D01*
X560729Y-297699D01*
X562039Y-299449D01*
X563568Y-300616D01*
X565096Y-301199D01*
X566624D01*
X568153Y-300616D01*
X569463Y-299741D01*
X570555Y-298575D01*
G01X584342Y-291866D02*
X585216Y-290991D01*
X585871Y-289533D01*
X586308Y-287490D01*
X585871Y-285741D01*
X584998Y-284574D01*
X583469Y-283699D01*
X577574D01*
Y-301199D01*
X584779D01*
X586308Y-300033D01*
X587181Y-298282D01*
X587618Y-296241D01*
X587181Y-294199D01*
X585871Y-292449D01*
X584342Y-291866D01*
X577574D01*
G01X593546Y-307032D02*
X606646D01*
G01X612574Y-301199D02*
Y-283699D01*
X622618Y-301199D01*
Y-283699D01*
G01X635096Y-301199D02*
X633349Y-300907D01*
X631821Y-299741D01*
X630511Y-297991D01*
X629637Y-295949D01*
X629201Y-293616D01*
Y-291282D01*
X629637Y-288949D01*
X630511Y-286907D01*
X631821Y-285158D01*
X633349Y-283991D01*
X635096Y-283699D01*
X636842Y-283991D01*
X638371Y-285158D01*
X639681Y-286907D01*
X640555Y-288949D01*
X640991Y-291282D01*
Y-293616D01*
X640555Y-295949D01*
X639681Y-297991D01*
X638371Y-299741D01*
X636842Y-300907D01*
X635096Y-301199D01*
G01X685937Y-283699D02*
X691396Y-301199D01*
X696855Y-283699D01*
G01X713263Y-301199D02*
X704529D01*
Y-283699D01*
X713263D01*
G01X709769Y-292157D02*
X704529D01*
G01X722029Y-301199D02*
Y-283699D01*
X727488D01*
X729234Y-284574D01*
X730326Y-285741D01*
X730763Y-288074D01*
X730326Y-290408D01*
X729016Y-291866D01*
X727488Y-292741D01*
X722029D01*
G01X727488D02*
X730763Y-301199D01*
G01X743896Y-301782D02*
X743459Y-301491D01*
Y-300907D01*
X743896Y-300616D01*
X744333Y-300907D01*
Y-301491D01*
X743896Y-301782D01*
G01X717646Y-346199D02*
Y-328699D01*
X715026Y-332199D01*
G01Y-346199D02*
X720266D01*
G01X898213Y-328699D02*
Y-346199D01*
X889479D01*
G01X881149Y-343575D02*
X879840Y-345033D01*
X878311Y-345907D01*
X876346Y-346199D01*
X874381Y-345616D01*
X872853Y-344449D01*
X871761Y-342408D01*
X871543Y-340074D01*
X871979Y-337741D01*
X873071Y-336282D01*
X874600Y-335116D01*
X876128Y-334824D01*
X877656Y-335116D01*
X879621Y-336282D01*
X878966Y-328699D01*
X873071D01*
G01X864305D02*
X858846Y-346199D01*
X853387Y-328699D01*
G01X836543Y-330158D02*
X837853Y-329282D01*
X839381Y-328699D01*
X841128D01*
X843093Y-329574D01*
X844621Y-331032D01*
X845713Y-332783D01*
X846586Y-335699D01*
X846805Y-338324D01*
X846368Y-340949D01*
X845713Y-342699D01*
X844403Y-344449D01*
X842874Y-345616D01*
X841346Y-346199D01*
X839818D01*
X838289Y-345616D01*
X836979Y-344741D01*
X835887Y-343575D01*
G01X819043Y-330158D02*
X820353Y-329282D01*
X821881Y-328699D01*
X823628D01*
X825593Y-329574D01*
X827121Y-331032D01*
X828213Y-332783D01*
X829086Y-335699D01*
X829305Y-338324D01*
X828868Y-340949D01*
X828213Y-342699D01*
X826903Y-344449D01*
X825374Y-345616D01*
X823846Y-346199D01*
X822318D01*
X820789Y-345616D01*
X819479Y-344741D01*
X818387Y-343575D01*
G01X819479Y-283699D02*
Y-301199D01*
X828213D01*
G01X845276D02*
Y-289533D01*
G01Y-291574D02*
X844403Y-290408D01*
X843092Y-289824D01*
X841564Y-289533D01*
X840036Y-290116D01*
X838726Y-291282D01*
X837852Y-293032D01*
X837416Y-295366D01*
X837852Y-297699D01*
X838726Y-299449D01*
X840036Y-300616D01*
X841564Y-301199D01*
X843092Y-300907D01*
X844403Y-300033D01*
X845276Y-298866D01*
G01X854261Y-306449D02*
X855571Y-307032D01*
X857318Y-306449D01*
X858409Y-305283D01*
X859283Y-303824D01*
X860592Y-299158D01*
X863431Y-289533D01*
G01X856444D02*
X860592Y-299158D01*
G01X873071Y-293324D02*
X880058D01*
X879403Y-291282D01*
X878311Y-290116D01*
X876783Y-289533D01*
X875254Y-289824D01*
X873944Y-290699D01*
X873071Y-292741D01*
X872634Y-294491D01*
Y-296241D01*
X873071Y-297991D01*
X874163Y-299741D01*
X875473Y-300907D01*
X877001Y-301199D01*
X878529Y-300616D01*
X880058Y-298866D01*
G01X890789Y-301199D02*
Y-289533D01*
G01Y-291866D02*
X891881Y-290699D01*
X892973Y-289824D01*
X894501Y-289533D01*
X895592Y-289824D01*
X896903Y-290699D01*
G01X959846Y-328699D02*
X962902Y-346199D01*
X966396Y-328699D01*
X969889Y-346199D01*
X972946Y-328699D01*
G01X979529Y-346199D02*
Y-328699D01*
X984769D01*
X986516Y-329574D01*
X987826Y-331616D01*
X988263Y-333949D01*
X987826Y-336282D01*
X986734Y-338032D01*
X984769Y-338908D01*
X979529D01*
G01X996811Y-346199D02*
Y-328699D01*
G01X1005981D02*
Y-346199D01*
G01Y-337449D02*
X996811D01*
G01X1016058Y-340366D02*
X1021734D01*
G01X1031593Y-346199D02*
Y-328699D01*
G01X1039889D02*
X1031593Y-339491D01*
G01X1041199Y-346199D02*
X1035304Y-334533D01*
G01X1058263Y-346199D02*
X1049529D01*
Y-328699D01*
X1058263D01*
G01X1054769Y-337157D02*
X1049529D01*
G01X1066374Y-346199D02*
Y-328699D01*
X1076418Y-346199D01*
Y-328699D01*
G01X1083874Y-346199D02*
Y-328699D01*
X1093918Y-346199D01*
Y-328699D01*
G01X961593Y-301199D02*
Y-283699D01*
X965959D01*
X967706Y-284574D01*
X969016Y-285741D01*
X970108Y-287490D01*
X970981Y-289533D01*
X971199Y-292449D01*
X970981Y-295366D01*
X970108Y-297408D01*
X969016Y-299158D01*
X967706Y-300324D01*
X965959Y-301199D01*
X961593D01*
G01X980621Y-293324D02*
X987608D01*
X986953Y-291282D01*
X985861Y-290116D01*
X984333Y-289533D01*
X982804Y-289824D01*
X981494Y-290699D01*
X980621Y-292741D01*
X980184Y-294491D01*
Y-296241D01*
X980621Y-297991D01*
X981713Y-299741D01*
X983023Y-300907D01*
X984551Y-301199D01*
X986079Y-300616D01*
X987608Y-298866D01*
G01X998121Y-299158D02*
X999213Y-300324D01*
X1000741Y-301199D01*
X1002051D01*
X1003361Y-300616D01*
X1004234Y-299741D01*
X1004671Y-298575D01*
X1004453Y-296824D01*
X1003579Y-295949D01*
X999649Y-294199D01*
X998776Y-292157D01*
X999213Y-290699D01*
X1000086Y-289824D01*
X1001396Y-289533D01*
X1002706Y-289824D01*
X1004016Y-290699D01*
G01X1018896Y-289533D02*
Y-301199D01*
G01Y-284866D02*
X1018459Y-284574D01*
Y-283991D01*
X1018896Y-283699D01*
X1019333Y-283991D01*
Y-284574D01*
X1018896Y-284866D01*
G01X1033339Y-305574D02*
X1034868Y-306741D01*
X1036614Y-307032D01*
X1038142Y-306741D01*
X1039453Y-305283D01*
X1040326Y-303241D01*
Y-289533D01*
G01Y-291866D02*
X1039453Y-290699D01*
X1038142Y-289824D01*
X1036614Y-289533D01*
X1034868Y-290116D01*
X1033776Y-291282D01*
X1032902Y-293324D01*
X1032466Y-295366D01*
X1032684Y-297116D01*
X1033558Y-299158D01*
X1034868Y-300616D01*
X1036614Y-301199D01*
X1037924Y-300907D01*
X1039453Y-299741D01*
X1040326Y-298575D01*
G01X1050184Y-301199D02*
Y-289533D01*
G01Y-292449D02*
X1051058Y-290991D01*
X1052368Y-289824D01*
X1054114Y-289533D01*
X1055642Y-289824D01*
X1056953Y-290991D01*
X1057608Y-293032D01*
Y-301199D01*
G01X1068121Y-293324D02*
X1075108D01*
X1074453Y-291282D01*
X1073361Y-290116D01*
X1071833Y-289533D01*
X1070304Y-289824D01*
X1068994Y-290699D01*
X1068121Y-292741D01*
X1067684Y-294491D01*
Y-296241D01*
X1068121Y-297991D01*
X1069213Y-299741D01*
X1070523Y-300907D01*
X1072051Y-301199D01*
X1073579Y-300616D01*
X1075108Y-298866D01*
G01X1085839Y-301199D02*
Y-289533D01*
G01Y-291866D02*
X1086931Y-290699D01*
X1088023Y-289824D01*
X1089551Y-289533D01*
X1090642Y-289824D01*
X1091953Y-290699D01*
G01X1132596Y-346199D02*
Y-328699D01*
X1129976Y-332199D01*
G01Y-346199D02*
X1135216D01*
G01X1150096D02*
Y-328699D01*
X1147476Y-332199D01*
G01Y-346199D02*
X1152716D01*
G01X1163666Y-346782D02*
X1171526Y-328699D01*
G01X1185096Y-346199D02*
Y-328699D01*
X1182476Y-332199D01*
G01Y-346199D02*
X1187716D01*
G01X1198448Y-338908D02*
X1199976Y-336866D01*
X1201286Y-335699D01*
X1203033Y-335116D01*
X1204561Y-335699D01*
X1205653Y-336866D01*
X1206526Y-338616D01*
X1206744Y-340657D01*
X1206526Y-342408D01*
X1205653Y-344158D01*
X1204342Y-345616D01*
X1202814Y-346199D01*
X1201068Y-345616D01*
X1199539Y-343866D01*
X1198666Y-341241D01*
X1198448Y-338324D01*
X1198884Y-334533D01*
X1199539Y-332490D01*
X1200631Y-330449D01*
X1202159Y-328991D01*
X1203688Y-328699D01*
X1205216Y-329282D01*
X1206308Y-330741D01*
G01X1216166Y-346782D02*
X1224026Y-328699D01*
G01X1233448Y-331616D02*
X1234758Y-329866D01*
X1236286Y-328991D01*
X1238033Y-328699D01*
X1240216Y-329282D01*
X1241744Y-330741D01*
X1242181Y-332490D01*
X1241963Y-334241D01*
X1241089Y-335699D01*
X1236723Y-338616D01*
X1234758Y-340657D01*
X1233448Y-343575D01*
X1233011Y-346199D01*
X1242181D01*
G01X1255096Y-328699D02*
X1253349Y-329282D01*
X1252039Y-330741D01*
X1251166Y-332490D01*
X1250511Y-334824D01*
X1250293Y-337449D01*
X1250511Y-340074D01*
X1251166Y-342408D01*
X1252039Y-344158D01*
X1253349Y-345616D01*
X1255096Y-346199D01*
X1256842Y-345616D01*
X1258153Y-344158D01*
X1259026Y-342408D01*
X1259681Y-340074D01*
X1259899Y-337449D01*
X1259681Y-334824D01*
X1259026Y-332490D01*
X1258153Y-330741D01*
X1256842Y-329282D01*
X1255096Y-328699D01*
G01X1272596Y-346199D02*
Y-328699D01*
X1269976Y-332199D01*
G01Y-346199D02*
X1275216D01*
G01X1285948Y-338908D02*
X1287476Y-336866D01*
X1288786Y-335699D01*
X1290533Y-335116D01*
X1292061Y-335699D01*
X1293153Y-336866D01*
X1294026Y-338616D01*
X1294244Y-340657D01*
X1294026Y-342408D01*
X1293153Y-344158D01*
X1291842Y-345616D01*
X1290314Y-346199D01*
X1288568Y-345616D01*
X1287039Y-343866D01*
X1286166Y-341241D01*
X1285948Y-338324D01*
X1286384Y-334533D01*
X1287039Y-332490D01*
X1288131Y-330449D01*
X1289659Y-328991D01*
X1291188Y-328699D01*
X1292716Y-329282D01*
X1293808Y-330741D01*
G01X1180293Y-301199D02*
Y-283699D01*
X1184659D01*
X1186406Y-284574D01*
X1187716Y-285741D01*
X1188808Y-287490D01*
X1189681Y-289533D01*
X1189899Y-292449D01*
X1189681Y-295366D01*
X1188808Y-297408D01*
X1187716Y-299158D01*
X1186406Y-300324D01*
X1184659Y-301199D01*
X1180293D01*
G01X1206526D02*
Y-289533D01*
G01Y-291574D02*
X1205653Y-290408D01*
X1204342Y-289824D01*
X1202814Y-289533D01*
X1201286Y-290116D01*
X1199976Y-291282D01*
X1199102Y-293032D01*
X1198666Y-295366D01*
X1199102Y-297699D01*
X1199976Y-299449D01*
X1201286Y-300616D01*
X1202814Y-301199D01*
X1204342Y-300907D01*
X1205653Y-300033D01*
X1206526Y-298866D01*
G01X1220096Y-283699D02*
Y-301199D01*
G01X1217039Y-289533D02*
X1223153D01*
G01X1234321Y-293324D02*
X1241308D01*
X1240653Y-291282D01*
X1239561Y-290116D01*
X1238033Y-289533D01*
X1236504Y-289824D01*
X1235194Y-290699D01*
X1234321Y-292741D01*
X1233884Y-294491D01*
Y-296241D01*
X1234321Y-297991D01*
X1235413Y-299741D01*
X1236723Y-300907D01*
X1238251Y-301199D01*
X1239779Y-300616D01*
X1241308Y-298866D01*
M02*
